G04 ================== begin FILE IDENTIFICATION RECORD ==================*
G04 Layout Name:  9048_F0T_Management_Board_D_brd_V04_1213_1625.brd*
G04 Film Name:    in2*
G04 File Format:  Gerber RS274X*
G04 File Origin:  Cadence Allegro 17.2-S081*
G04 Origin Date:  Tue Dec 13 16:31:11 2022*
G04 *
G04 Layer:  DRAWING FORMAT/TITLE_BLOCK_A*
G04 Layer:  VIA CLASS/IN2*
G04 Layer:  PIN/IN2*
G04 Layer:  MANUFACTURING/PHOTOPLOT_OUTLINE*
G04 Layer:  ETCH/IN2*
G04 Layer:  DRAWING FORMAT/TITLE_BLOCK*
G04 Layer:  DRAWING FORMAT/TITLE_DATA_IN2*
G04 *
G04 Offset:    (0.00 0.00)*
G04 Mirror:    No*
G04 Mode:      Positive*
G04 Rotation:  0*
G04 FullContactRelief:  No*
G04 UndefLineWidth:     6.00*
G04 ================== end FILE IDENTIFICATION RECORD ====================*
%FSLAX25Y25*MOIN*%
%IR0*IPPOS*OFA0.00000B0.00000*MIA0B0*SFA1.00000B1.00000*%
%ADD11C,.02*%
%ADD12C,.018*%
%ADD10C,.085*%
%ADD13C,.01*%
%ADD14C,.015*%
%ADD15C,.006*%
%ADD16C,.0042*%
%ADD17C,.03004*%
%ADD18C,.02604*%
%ADD19C,.02804*%
G75*
%LPD*%
G75*
G36*
G01X331081Y468024D02*
X332262D01*
X332646Y467640D01*
Y451968D01*
G03X336614Y448000I3969J1D01*
G01X346457D01*
G02X352331Y442126I0J-5874D01*
G01Y336646D01*
X345472D01*
G03X341504Y332678I0J-3968D01*
G01Y322834D01*
G03X345472Y318866I3968J0D01*
G01X352331D01*
Y7874D01*
G02X346457Y2000I-5874J0D01*
G01X7874D01*
G02X2000Y7874I0J5874D01*
G01Y318866D01*
X8858D01*
G03X12827Y322835I0J3969D01*
G01Y332677D01*
G03X8858Y336646I-3969J0D01*
G01X2000D01*
Y442126D01*
G02X7874Y448000I5874J0D01*
G01X17717D01*
G03X21685Y451968I-1J3969D01*
G01Y467365D01*
X22132Y467812D01*
X23372D01*
X23682Y467502D01*
Y451968D01*
G02X17717Y446002I-5966J0D01*
G01X7874D01*
G03X3998Y442126I0J-3876D01*
G01Y338644D01*
X8858D01*
G02X13013Y336959I-1J-5967D01*
G01X13139Y336833D01*
G02X14822Y332811I-4282J-4155D01*
G01Y322700D01*
G02X8858Y316868I-5964J133D01*
G01X3998D01*
Y308725D01*
G03X3996Y308669I1209J-71D01*
G01Y120892D01*
G03X3998Y120836I1211J15D01*
G01Y7874D01*
G03X7874Y3998I3876J0D01*
G01X250842D01*
X301602D01*
X346457D01*
G03X350334Y7874I0J3877D01*
G01Y316868D01*
X345472D01*
G02X339506Y322834I0J5967D01*
G01Y332678D01*
G02X345472Y338644I5966J-1D01*
G01X350334D01*
Y442126D01*
G03X346459Y446002I-3876J0D01*
G01X336614D01*
G02X330648Y451968I0J5966D01*
G01Y467591D01*
X331081Y468024D01*
G37*
G36*
G01X35656Y315972D02*
X37314Y314314D01*
G03X38100Y313988I787J786D01*
G01X44700D01*
G03X45486Y314314I-1J1112D01*
G01X46086Y314914D01*
X47208Y313791D01*
Y313564D01*
G03Y310596I232J-1484D01*
G01Y310175D01*
G03Y307207I232J-1484D01*
G01Y305717D01*
X47059Y305678D01*
G03X45938Y304225I381J-1453D01*
G03X46463Y303084I1502J0D01*
G02Y302477I-260J-304D01*
G03X45938Y301336I977J-1141D01*
G03X47059Y299883I1502J0D01*
G01X47208Y299844D01*
Y278978D01*
G02X46685Y278598I-400J0D01*
G03X46220Y278672I-466J-1428D01*
G03Y275668I0J-1502D01*
G03X46685Y275742I-1J1502D01*
G02X47208Y275362I123J-380D01*
G01Y265208D01*
X43600Y261600D01*
Y232400D01*
X32140Y220940D01*
Y203110D01*
X34320Y200930D01*
X37960D01*
X41960Y196930D01*
Y191331D01*
X41992Y191299D01*
X42000Y191228D01*
G03X42636Y189885I2200J220D01*
G01X53778Y178743D01*
Y131068D01*
X53304Y130594D01*
X53164Y130703D01*
G03X52237Y131024I-928J-1181D01*
G03X51350Y130734I0J-1501D01*
G02X50719Y130994I-236J323D01*
G03X49236Y132260I-1483J-236D01*
G03X47734Y130758I0J-1502D01*
G03X48313Y129573I1502J0D01*
G02Y128943I-246J-315D01*
G03X47734Y127758I923J-1185D01*
G03X47833Y127223I1502J1D01*
G02X47460Y126680I-374J-143D01*
G01X42512D01*
G02X42139Y127223I1J400D01*
G03X42238Y127758I-1403J536D01*
G03X41659Y128943I-1502J0D01*
G02Y129573I246J315D01*
G03X42238Y130758I-923J1185D01*
G03X39234I-1502J0D01*
G03X39813Y129573I1502J0D01*
G02Y128943I-246J-315D01*
G03X39234Y127758I923J-1185D01*
G03X39333Y127223I1502J1D01*
G02X38960Y126680I-374J-143D01*
G01X34012D01*
G02X33639Y127223I1J400D01*
G03X33738Y127758I-1403J536D01*
G03X33159Y128943I-1502J0D01*
G02Y129573I246J315D01*
G03X33738Y130758I-923J1185D01*
G03X30734I-1502J0D01*
G03X31313Y129573I1502J0D01*
G02Y128943I-246J-315D01*
G03X30734Y127758I923J-1185D01*
G03X30833Y127223I1502J1D01*
G02X30460Y126680I-374J-143D01*
G01X25512D01*
G02X25139Y127223I1J400D01*
G03X25238Y127758I-1403J536D01*
G03X24659Y128943I-1502J0D01*
G02Y129573I246J315D01*
G03X25238Y130758I-923J1185D01*
G03X22234I-1502J0D01*
G03X22813Y129573I1502J0D01*
G02Y128943I-246J-315D01*
G03X22234Y127758I923J-1185D01*
G03X22333Y127223I1502J1D01*
G02X21960Y126680I-374J-143D01*
G01X20381D01*
X15221Y131840D01*
Y221121D01*
X16500Y222400D01*
X22100D01*
X23100Y223400D01*
Y228400D01*
X21900Y229600D01*
X17221D01*
X15221Y231600D01*
Y250921D01*
X18740Y254440D01*
Y259571D01*
X15221Y263090D01*
Y299665D01*
X15223Y299679D01*
G03X15238Y299891I-1487J212D01*
G03X15223Y300103I-1502J0D01*
G01X15221Y300117D01*
Y303054D01*
X15223Y303068D01*
G03X15238Y303280I-1487J212D01*
G03X15223Y303492I-1502J0D01*
G01X15221Y303506D01*
Y306721D01*
X24409Y315908D01*
X26610D01*
G03X26969Y315963I-2J1212D01*
G01X26998Y315972D01*
X28800D01*
G02X29199Y315557I-1J-400D01*
G03X29198Y315500I1501J-55D01*
G03X32202I1502J0D01*
G03X32201Y315557I-1502J2D01*
G02X32600Y315972I400J15D01*
G01X35656D01*
G37*
G36*
G01X38828Y468024D02*
X40009D01*
X40382Y467651D01*
Y451968D01*
G03X44350Y448000I3969J1D01*
G01X45976D01*
X46336Y447640D01*
Y446364D01*
X45974Y446002D01*
X44350D01*
G02X38384Y451968I0J5966D01*
G01Y467580D01*
X38828Y468024D01*
G37*
G36*
G01X70400Y157000D02*
X77500D01*
X84281Y150219D01*
X84296Y150174D01*
G03X84755Y149431I1804J601D01*
G01X87500Y146687D01*
Y134000D01*
X94400Y127100D01*
Y117369D01*
G02X93685Y117123I-400J0D01*
G03X92500Y117702I-1185J-923D01*
G03Y114698I0J-1502D01*
G03X93685Y115277I0J1502D01*
G02X94400Y115031I315J-246D01*
G01Y84528D01*
X94222Y84350D01*
X94019Y84146D01*
X92812D01*
X92763Y84276D01*
G03X92281Y84930I-1405J-531D01*
G02Y85560I246J315D01*
G03Y87930I-923J1185D01*
G02Y88560I246J315D01*
G03Y90930I-923J1185D01*
G02Y91560I246J315D01*
G03X92860Y92745I-923J1185D01*
G03X89856I-1502J0D01*
G03X90435Y91560I1502J0D01*
G02Y90930I-246J-315D01*
G03Y88560I923J-1185D01*
G02Y87930I-246J-315D01*
G03Y85560I923J-1185D01*
G02Y84930I-246J-315D01*
G03X89953Y84276I923J-1185D01*
G01X89904Y84146D01*
X76211D01*
X76162Y84276D01*
G03X75680Y84930I-1405J-531D01*
G02Y85560I246J315D01*
G03Y87930I-923J1185D01*
G02Y88560I246J315D01*
G03Y90930I-923J1185D01*
G02Y91560I246J315D01*
G03X76259Y92745I-923J1185D01*
G03X73255I-1502J0D01*
G03X73834Y91560I1502J0D01*
G02Y90930I-246J-315D01*
G03Y88560I923J-1185D01*
G02X73839Y87934I-246J-315D01*
G03X73255Y86745I918J-1189D01*
G03X73263Y86588I1502J-2D01*
G01X73265Y86569D01*
G03X73834Y85560I1492J176D01*
G02Y84930I-246J-315D01*
G03X73352Y84276I923J-1185D01*
G01X73303Y84146D01*
X68680D01*
X67534Y85292D01*
X66532Y86295D01*
Y114416D01*
X68626Y120527D01*
Y128032D01*
G03X68628Y128100I-1500J78D01*
G03X68626Y128168I-1502J-10D01*
G01Y136969D01*
X67824Y137772D01*
Y154423D01*
X70400Y157000D01*
G37*
G36*
G01X89077Y313045D02*
X76413D01*
X74516Y311148D01*
Y297561D01*
X75182Y296895D01*
X89026D01*
X89385Y297254D01*
Y312737D01*
X89077Y313045D01*
G37*
G36*
G01X87839Y376600D02*
X88100D01*
X89533Y375167D01*
X89505Y375056D01*
G03X89464Y374733I1261J-324D01*
G03X89700Y373985I1303J0D01*
G01Y372332D01*
G03Y370836I1067J-748D01*
G01Y366070D01*
G03Y364574I1067J-748D01*
G01Y362921D01*
G03X89466Y362239I1066J-747D01*
G01X89462Y362162D01*
X89117Y361817D01*
X88913Y362021D01*
X88917Y362110D01*
G03X88919Y362173I-1300J73D01*
G03X87617Y360871I-1302J0D01*
G03X87680Y360873I-10J1302D01*
G01X87769Y360877D01*
X87973Y360673D01*
X87627Y360327D01*
X87550Y360323D01*
G03X86382Y359436I67J-1300D01*
G01X86337Y359300D01*
X81700D01*
X79596Y357196D01*
G02X78966Y356930I-396J58D01*
G03X78206Y357175I-760J-1056D01*
G03Y354571I0J-1302D01*
G03X78966Y354816I0J1301D01*
G02X79600Y354491I234J-324D01*
G01Y352700D01*
X80906Y351394D01*
G02X80795Y350750I-283J-283D01*
G03X80053Y349574I561J-1176D01*
G03X81307Y348273I1302J0D01*
G02X81500Y348073I-7J-200D01*
G01Y347926D01*
G02X81307Y347726I-200J0D01*
G03Y345124I48J-1301D01*
G02X81500Y344924I-7J-200D01*
G01Y343996D01*
X81350Y343958D01*
G03Y341242I351J-1358D01*
G01X81500Y341204D01*
Y338554D01*
X81371Y338506D01*
G03X80567Y337792I529J-1406D01*
G02X79936Y337687I-355J185D01*
G03X78900Y338102I-1036J-1086D01*
G03Y335098I0J-1502D01*
G03X80233Y335908I0J1502D01*
G02X80864Y336013I355J-185D01*
G03X81371Y335694I1037J1086D01*
G01X81500Y335646D01*
Y325400D01*
X79600Y323500D01*
X78322D01*
X78269Y323618D01*
G03X75531I-1369J-618D01*
G01X75478Y323500D01*
X74508D01*
X74478Y323665D01*
G03X73000Y324902I-1478J-264D01*
G03X72120Y324617I0J-1501D01*
G01X71982Y324518D01*
X71602Y324899D01*
Y325830D01*
G03X71247Y326687I-1212J0D01*
G01X69600Y328333D01*
Y345433D01*
G03Y347417I-842J992D01*
G01Y348582D01*
G03Y350566I-842J992D01*
G01Y351732D01*
G03Y353716I-842J992D01*
G01Y354881D01*
G03Y356865I-842J992D01*
G01Y358031D01*
G03Y360015I-842J992D01*
G01Y361181D01*
G03Y363165I-842J992D01*
G01Y364330D01*
G03Y366314I-842J992D01*
G01Y368497D01*
X71247Y370143D01*
G03X71427Y370373I-857J856D01*
G03X71906Y370282I478J1211D01*
G03X73208Y371584I0J1302D01*
G03X72491Y372747I-1302J0D01*
G02X72388Y373388I179J358D01*
G01X72705Y373705D01*
X72714Y373712D01*
G03X72927Y373925I-808J1021D01*
G01X72934Y373934D01*
X73252Y374252D01*
G02X73892Y374149I283J-283D01*
G03X75056Y373431I1164J585D01*
G03X76358Y374733I0J1302D01*
G03X75640Y375897I-1303J0D01*
G02X75537Y376537I180J357D01*
G01X75600Y376600D01*
X77984D01*
X78000Y376597D01*
G03X78206Y376581I204J1286D01*
G03X78412Y376597I2J1302D01*
G01X78428Y376600D01*
X81133D01*
X81149Y376597D01*
G03X81355Y376581I204J1286D01*
G03X81561Y376597I2J1302D01*
G01X81577Y376600D01*
X87395D01*
X87411Y376597D01*
G03X87617Y376581I204J1286D01*
G03X87823Y376597I2J1302D01*
G01X87839Y376600D01*
G37*
G36*
G01X72600Y410400D02*
X76493D01*
G02X76780Y409722I0J-400D01*
G03X76358Y408678I1080J-1044D01*
G03X77860Y407176I1502J0D01*
G03X78523Y407330I0J1502D01*
G02X79100Y406972I177J-359D01*
G01Y404600D01*
X82900Y400800D01*
X92400D01*
X98600Y394600D01*
Y388601D01*
G02X97934Y388303I-400J0D01*
G03X97066Y388634I-867J-971D01*
G03Y386030I0J-1302D01*
G03X97934Y386361I1J1302D01*
G02X98600Y386063I266J-298D01*
G01Y384100D01*
X97600Y383100D01*
X95475D01*
G02X95109Y383660I0J400D01*
G03X95218Y384182I-1193J522D01*
G03X92614I-1302J0D01*
G03X92723Y383660I1302J0D01*
G02X92357Y383100I-366J-160D01*
G01X92200D01*
X91852Y383448D01*
X91920Y383579D01*
G03X92068Y384182I-1154J603D01*
G03X89464I-1302J0D01*
G03X89466Y384111I1302J1D01*
G01Y383900D01*
X88917D01*
Y384111D01*
G03X88919Y384182I-1300J72D01*
G03X87617Y385484I-1302J0D01*
G03X86318Y384272I0J-1302D01*
G02X85919Y383900I-399J28D01*
G01X83053D01*
G02X82654Y384272I0J400D01*
G03X80056I-1299J-90D01*
G02X79657Y383900I-399J28D01*
G01X75300D01*
X74200Y382800D01*
X70600D01*
X70000Y383400D01*
Y383793D01*
X70008Y383821D01*
G03Y384543I-1252J361D01*
G01X70000Y384571D01*
Y392701D01*
G02X70533Y393078I400J0D01*
G03X71000Y392998I467J1323D01*
G03Y395802I0J1402D01*
G03X70533Y395722I0J-1403D01*
G02X70000Y396099I-133J377D01*
G01Y407321D01*
X70141Y407364D01*
G03X71202Y408800I-441J1436D01*
G03X71199Y408902I-1502J7D01*
G01X71192Y408992D01*
X72600Y410400D01*
G37*
G36*
G01X141491Y225328D02*
X146678D01*
X147424Y224582D01*
Y215996D01*
X146775Y215347D01*
X142204D01*
G03X142038Y215538I-1401J-1050D01*
G01X141059Y216518D01*
Y217582D01*
X141138Y217662D01*
G03X141652Y218900I-1237J1239D01*
G01Y223100D01*
G03X141138Y224338I-1751J-1D01*
G01X141059Y224418D01*
Y224896D01*
X141491Y225328D01*
G37*
G36*
G01X145895Y426050D02*
G03I-530J0D01*
G37*
G36*
G01X164085Y227800D02*
X165400D01*
X165941Y227259D01*
G02X165795Y226601I-283J-282D01*
G03X164806Y225189I513J-1412D01*
G03X165675Y223827I1502J0D01*
G02X165862Y223283I-169J-362D01*
G03X165698Y222600I1338J-682D01*
G03X167200Y221098I1502J0D01*
G03X167428Y221115I3J1502D01*
G02X167888Y220720I60J-395D01*
G01Y218088D01*
X167200Y217400D01*
X162000D01*
X161502Y217898D01*
Y219498D01*
G02X161964Y219893I400J0D01*
G03X162200Y219874I238J1483D01*
G03Y222878I0J1502D01*
G03X160834Y222002I0J-1503D01*
G02X160188Y221885I-364J166D01*
G01X158732Y223342D01*
Y227632D01*
X158900Y227800D01*
X162915D01*
X162950Y227786D01*
G03X163500Y227682I549J1398D01*
G03X164050Y227786I1J1502D01*
G01X164085Y227800D01*
G37*
G36*
G01X212000Y296930D02*
X219399D01*
X222156Y294173D01*
X222149Y294081D01*
G03X222144Y293960I1497J-122D01*
G03X222860Y292680I1502J0D01*
G02X222865Y292002I-210J-341D01*
G03X222170Y290735I807J-1267D01*
G03X223573Y289236I1502J0D01*
G02X223760Y289037I-13J-199D01*
G01Y277473D01*
X223443Y277157D01*
G03X223088Y276300I857J-857D01*
G01Y263870D01*
X222287Y263068D01*
X222251Y263052D01*
G03X221331Y261668I581J-1384D01*
G03X221869Y260516I1502J0D01*
G01Y244843D01*
G02X221370Y244456I-400J0D01*
G03X221000Y244502I-369J-1456D01*
G03Y241498I0J-1502D01*
G03X221370Y241544I1J1502D01*
G02X221869Y241157I99J-387D01*
G01Y238372D01*
G02X221165Y238112I-400J0D01*
G03X220100Y238602I-1065J-912D01*
G03X218698Y237200I0J-1402D01*
G03X219848Y235821I1402J0D01*
G01X219909Y235810D01*
X220095Y235624D01*
X219943Y235473D01*
G03X219748Y235217I858J-856D01*
G01X219735Y235194D01*
X219546Y235005D01*
Y233850D01*
G02X219171Y233450I-400J-1D01*
G03X217951Y232151I82J-1299D01*
G03X219253Y230849I1302J0D01*
G03X219334Y230851I8J1302D01*
G02X219546Y230652I12J-199D01*
G01Y230501D01*
G02X219334Y230302I-200J0D01*
G03X219253Y230304I-73J-1300D01*
G03Y227700I0J-1302D01*
G03X219334Y227702I8J1302D01*
G02X219546Y227503I12J-199D01*
G01Y227353D01*
G02X219339Y227153I-200J0D01*
G03X219290Y227154I-51J-1301D01*
G03X217988Y225852I0J-1302D01*
G03X218491Y224824I1302J0D01*
G01X218501Y224816D01*
X218651Y224666D01*
X218433Y224448D01*
G03X218078Y223591I857J-857D01*
G01Y223181D01*
X218066Y223148D01*
G03X217988Y222703I1224J-444D01*
G03X219290Y221401I1302J0D01*
G03X219339Y221402I-2J1302D01*
G02X219546Y221202I7J-200D01*
G01Y221052D01*
G02X219334Y220853I-200J0D01*
G03X219253Y220855I-73J-1300D01*
G03X217951Y219553I0J-1302D01*
G03X218169Y218831I1302J-1D01*
G02X217976Y218235I-333J-221D01*
G03X217543Y217957I423J-1135D01*
G01X213841Y214254D01*
X213705Y214343D01*
G03X212991Y214556I-714J-1090D01*
G03X211689Y213254I0J-1302D01*
G03X211695Y213130I1302J1D01*
G01X211696Y213121D01*
Y212912D01*
X211137D01*
Y213121D01*
X211138Y213130D01*
G03X211144Y213254I-1296J125D01*
G03X208540I-1302J0D01*
G03X208553Y213068I1302J-2D01*
G02X208418Y212850I-198J-28D01*
G03X207943Y212557I382J-1150D01*
G01X205501Y210115D01*
G02X204825Y210328I-282J283D01*
G03X203542Y211406I-1283J-224D01*
G03X202240Y210104I0J-1302D01*
G03X202671Y209136I1303J0D01*
G02X202403Y208439I-268J-297D01*
G01X201532D01*
G02X201264Y209136I0J400D01*
G03X201695Y210104I-872J968D01*
G03X199091I-1302J0D01*
G03X199522Y209136I1303J0D01*
G02X199254Y208439I-268J-297D01*
G01X195121D01*
X193820Y209740D01*
Y217856D01*
G02X194190Y218255I400J0D01*
G03X195396Y219553I-96J1298D01*
G03X194094Y220855I-1302J0D01*
G03X194030Y220853I9J-1302D01*
G02X193820Y221053I-10J200D01*
G01Y221203D01*
G02X194030Y221403I200J0D01*
G03X194094Y221401I73J1300D01*
G03X195396Y222703I0J1302D01*
G03X195338Y223086I-1302J-1D01*
G02X195721Y223604I382J118D01*
G01X196115D01*
Y223354D01*
X196092Y223311D01*
G03X195941Y222703I1151J-609D01*
G03X198545I1302J0D01*
G03X198487Y223086I-1302J-1D01*
G02X198870Y223604I382J118D01*
G01X200662D01*
X200665Y223607D01*
X201264Y223009D01*
Y222105D01*
G03X201083Y221957I673J-1008D01*
G01X199875Y220748D01*
X199843Y220733D01*
G03X199091Y219553I550J-1180D01*
G03X200393Y218251I1302J0D01*
G03X201461Y218809I0J1301D01*
G02X202072Y218863I328J-229D01*
G01X202693Y218242D01*
X208742D01*
X210386Y219886D01*
X210463Y219890D01*
G03X211258Y220243I-61J1210D01*
G01X212209Y221194D01*
G03X212456Y221553I-858J855D01*
G03X212991Y221438I535J1187D01*
G03Y224042I0J1302D01*
G03X212860Y224035I4J-1302D01*
G01X212850Y224034D01*
X212640D01*
Y224596D01*
X212850D01*
X212860Y224595D01*
G03X212991Y224588I135J1295D01*
G03Y227192I0J1302D01*
G03X212860Y227185I4J-1302D01*
G01X212850Y227184D01*
X212640D01*
Y227708D01*
X212850D01*
X212860Y227707D01*
G03X212991Y227700I135J1295D01*
G03X214293Y229002I0J1302D01*
G03X214209Y229463I-1302J1D01*
G03X214545Y229700I-520J1094D01*
G01X215767Y230922D01*
G03X216122Y231779I-857J857D01*
G01Y237310D01*
G03X215767Y238167I-1212J0D01*
G01X213700Y240233D01*
Y241840D01*
X213332Y242209D01*
Y242779D01*
G02X214019Y243057I400J0D01*
G03X215100Y242598I1081J1043D01*
G03X216602Y244100I0J1502D01*
G03X216154Y245170I-1502J0D01*
G02X216238Y245803I281J285D01*
G03X217002Y247111I-738J1308D01*
G03X215500Y248613I-1502J0D01*
G03X214394Y248128I-1J-1502D01*
G02X213700Y248398I-294J271D01*
G01Y248625D01*
X214512Y249436D01*
G03X214866Y250293I-857J856D01*
G01Y251424D01*
G02X215318Y251820I400J-1D01*
G03X215510Y251808I190J1490D01*
G03X217012Y253310I0J1502D01*
G03X216974Y253645I-1502J-1D01*
G02X217246Y254116I390J89D01*
G03X218302Y255550I-446J1434D01*
G03X215298I-1502J0D01*
G03X215384Y255049I1502J0D01*
G02X215232Y254786I-189J-66D01*
G03X215119Y254760I280J-1476D01*
G01X215093Y254753D01*
X214866D01*
Y256153D01*
G03X214724Y256724I-1219J0D01*
G01X214700Y256768D01*
Y260136D01*
G03Y262828I-666J1346D01*
G01Y263107D01*
X215212Y263618D01*
G03X215566Y264475I-857J856D01*
G01Y268456D01*
G03X215212Y269313I-1211J1D01*
G01X213397Y271128D01*
G02X213591Y271800I283J282D01*
G03X214760Y273265I-333J1465D01*
G03X211756I-1502J0D01*
G01Y273253D01*
X211757Y273169D01*
X211556Y272968D01*
X211200Y273324D01*
Y296130D01*
X212000Y296930D01*
G37*
G36*
G01X187900Y284905D02*
X197382D01*
X197578Y284708D01*
Y272003D01*
X197521Y271864D01*
X195369Y269712D01*
G02X194728Y269816I-283J283D01*
G03X193386Y270644I-1342J-674D01*
G03X193388Y267640I0J-1502D01*
G02X193589Y267439I1J-200D01*
G03X193588Y267430I1197J-138D01*
G01Y259618D01*
X192857Y258886D01*
X192797Y258874D01*
G03X191582Y257400I287J-1474D01*
G03X191748Y256714I1502J0D01*
G01X191770Y256671D01*
Y237967D01*
G02X191585Y237768I-200J0D01*
G03X190291Y236370I108J-1398D01*
G03X191693Y234968I1402J0D01*
G03X192618Y235317I-1J1402D01*
G01X194055Y233880D01*
Y233464D01*
X193887Y233436D01*
G03X192792Y232151I206J-1285D01*
G03X194094Y230849I1302J0D01*
G03X195380Y231947I0J1302D01*
G01X195390Y232011D01*
X195577Y232199D01*
X195993Y231783D01*
X196008Y231738D01*
G03X196830Y230916I1235J413D01*
G01X196875Y230901D01*
X197291Y230485D01*
X197103Y230298D01*
X197039Y230288D01*
G03X195941Y229002I204J-1286D01*
G03X197243Y227700I1302J0D01*
G03X197411Y227711I-1J1302D01*
G02X197862Y227314I51J-397D01*
G01Y225186D01*
X197303Y224627D01*
X195583D01*
G02X195233Y225221I0J400D01*
G03X195396Y225852I-1140J631D01*
G03X192792I-1302J0D01*
G03X192955Y225221I1303J0D01*
G02X192605Y224627I-350J-194D01*
G01X190221D01*
X189200Y225648D01*
Y229730D01*
X187582Y231348D01*
Y233330D01*
G03X187577Y233447I-1412J-2D01*
G01X187574Y233483D01*
G03X187541Y233691I-1407J-117D01*
G01X187532Y233729D01*
G03X187452Y233967I-1373J-329D01*
G01X187432Y234013D01*
G03X187265Y234300I-1295J-561D01*
G01X187216Y234365D01*
G03X187087Y234513I-1126J-851D01*
G01X183212Y238389D01*
Y251119D01*
X184046Y253136D01*
G03X184077Y253217I-1302J545D01*
G01X184088Y253249D01*
G03X184103Y253297I-1339J445D01*
G01X184131Y253389D01*
G03X184145Y253436I-1345J426D01*
G01X184153Y253466D01*
G03X184173Y253555I-1366J354D01*
G01X185068Y258057D01*
G03X185080Y258121I-1381J292D01*
G01X185085Y258154D01*
G03X185092Y258215I-1398J191D01*
G01X185101Y258299D01*
G03X185106Y258348I-1401J168D01*
G01X185108Y258376D01*
G03X185112Y258477I-1408J106D01*
G01Y260490D01*
G03X185082Y260779I-1412J-1D01*
G01X185060Y260884D01*
G03X184994Y261107I-1382J-288D01*
G01X184987Y261125D01*
G03X184975Y261152I-1295J-559D01*
G01X184899Y261337D01*
X185948Y262386D01*
Y269535D01*
G03Y271865I-948J1165D01*
G01Y277051D01*
X186811Y277914D01*
G03X187224Y278912I-999J998D01*
G01Y284229D01*
X187900Y284905D01*
G37*
G36*
G01X199300Y265121D02*
X199588D01*
X199608Y264944D01*
G03X201100Y263618I1492J176D01*
G03X202141Y264037I0J1503D01*
G01X202283Y264173D01*
X203091Y263365D01*
X203423Y262564D01*
G03X203685Y262171I1120J463D01*
G01X204264Y261593D01*
Y259153D01*
G03Y257447I1235J-853D01*
G01Y252578D01*
X202012Y250327D01*
G03X201658Y249470I857J-856D01*
G01Y245965D01*
G03X202012Y245108I1211J-1D01*
G01X202250Y244871D01*
Y244764D01*
X204264Y242750D01*
Y236972D01*
G02X203788Y236579I-400J0D01*
G03X203542Y236603I-249J-1278D01*
G03Y233999I0J-1302D01*
G03X204589Y234527I0J1302D01*
G02X205193Y234572I321J-238D01*
G01X205963Y233802D01*
G02X205918Y233198I-283J-283D01*
G03X205390Y232151I774J-1047D01*
G03X206692Y230849I1302J0D01*
G03X207178Y230943I0J1303D01*
G03X207366Y230700I1045J614D01*
G01X207830Y230237D01*
X207570Y229978D01*
X207433Y230073D01*
G03X206692Y230304I-740J-1071D01*
G03Y227700I0J-1302D01*
G03X207883Y228477I0J1301D01*
G02X208532Y228598I366J-162D01*
G01X208647Y228484D01*
X208662Y228452D01*
G03X209757Y227703I1180J550D01*
G01X209832Y227698D01*
X210177Y227353D01*
X209974Y227150D01*
X209887Y227153D01*
G03X209842Y227154I-51J-1301D01*
G03Y224550I0J-1302D01*
G03X209927Y224553I-3J1302D01*
G02X210140Y224353I13J-199D01*
G01Y224202D01*
G02X209927Y224002I-200J-1D01*
G03X209842Y224005I-88J-1299D01*
G03X208540Y222703I0J-1302D01*
G03X208551Y222537I1302J3D01*
G01X208552Y222524D01*
Y222312D01*
X207982D01*
Y222524D01*
X207983Y222537D01*
G03X207994Y222703I-1291J169D01*
G03X206692Y224005I-1302J0D01*
G03X205390Y222709I0J-1302D01*
G02X204990Y222312I-400J3D01*
G01X202276D01*
Y223398D01*
X202266Y223409D01*
Y223424D01*
X201318Y224370D01*
G02X201317Y224935I283J283D01*
G03X201695Y225852I-923J917D01*
G03X200393Y227154I-1302J0D01*
G03X199529Y226826I0J-1302D01*
G02X198864Y227126I-265J300D01*
G01Y227728D01*
G02X199529Y228028I400J0D01*
G03X200393Y227700I864J974D01*
G03Y230304I0J1302D01*
G03X199529Y229976I0J-1302D01*
G02X198864Y230276I-265J300D01*
G01Y230532D01*
X198165Y231231D01*
G03X198545Y232151I-922J919D01*
G03X197243Y233453I-1302J0D01*
G03X196311Y233061I-1J-1302D01*
G01X193094Y236278D01*
X193095Y236361D01*
Y236370D01*
G03X192822Y237201I-1401J0D01*
G01Y252422D01*
X194222Y253822D01*
X194324Y253806D01*
G03X194386Y253797I247J1482D01*
G02X194738Y253406I-48J-397D01*
G03X196240Y251928I1502J24D01*
G03X197742Y253430I0J1502D01*
G03X196686Y254864I-1502J0D01*
G02X196521Y255529I118J382D01*
G01X197457Y256464D01*
G03X197812Y257321I-857J857D01*
G01Y263632D01*
X199300Y265121D01*
G37*
G36*
G01X218382Y115769D02*
X231272D01*
Y111975D01*
X231133Y111930D01*
G03Y109070I459J-1430D01*
G01X231272Y109025D01*
Y105350D01*
X217952D01*
Y112624D01*
X217960Y112652D01*
G03X218012Y113000I-1160J351D01*
G01Y115398D01*
X218382Y115769D01*
G37*
G36*
G01X258732Y191888D02*
X261272D01*
X261310Y191850D01*
Y177260D01*
X263310Y175260D01*
X268340D01*
X275700Y167900D01*
Y143980D01*
X271890Y140170D01*
X268372D01*
G03X268145Y140445I-1574J-1068D01*
G01X266102Y142488D01*
Y146212D01*
X267287Y147397D01*
G03X267844Y148742I-1345J1345D01*
G01Y148907D01*
G02X268285Y149305I400J0D01*
G03X268442Y149297I155J1494D01*
G03X269944Y150799I0J1502D01*
G03X269574Y151786I-1501J0D01*
G02Y152312I302J263D01*
G03X269944Y153299I-1131J987D01*
G03X268442Y154801I-1502J0D01*
G03X267455Y154431I0J-1501D01*
G02X266929I-263J302D01*
G03X265942Y154801I-987J-1131D01*
G03X264924Y154403I0J-1501D01*
G02X264367Y154417I-271J294D01*
G03X263294Y154868I-1073J-1051D01*
G03X261792Y153366I0J-1502D01*
G03X262076Y152488I1502J1D01*
G02X262020Y151958I-325J-234D01*
G03X261528Y150846I1011J-1112D01*
G03X262923Y149348I1502J0D01*
G02X263177Y148666I-29J-399D01*
G01X262855Y148345D01*
G03X262848Y148338I1342J-1349D01*
G02X262281Y148336I-284J281D01*
G01X260802Y149816D01*
Y172050D01*
G03X260447Y172907I-1212J0D01*
G01X258517Y174837D01*
G03X257660Y175192I-857J-857D01*
G01X255597D01*
G02X255198Y175569I0J400D01*
G03X253898Y176798I-1300J-73D01*
G03X252596Y175496I0J-1302D01*
G03X252599Y175405I1302J-3D01*
G01X252600Y175398D01*
Y175192D01*
X252047D01*
Y175398D01*
X252048Y175405D01*
G03X252051Y175496I-1299J88D01*
G03X249447I-1302J0D01*
G03X249510Y175097I1302J1D01*
G03X249158Y174870I471J-1116D01*
G02X248833Y175081I-135J147D01*
G03X248901Y175496I-1234J415D01*
G03X247599Y174194I-1302J0D01*
G03X248014Y174262I0J1302D01*
G02X248224Y173936I64J-190D01*
G03X248041Y173680I886J-827D01*
G01X239220D01*
X238400Y174500D01*
Y187871D01*
X240641Y190112D01*
X240767Y190056D01*
G03X241300Y189942I533J1189D01*
G03X242602Y191244I0J1302D01*
G03X242588Y191431I-1302J-3D01*
G02X242984Y191888I396J57D01*
G01X245915D01*
G02X246311Y191431I0J-400D01*
G03X246297Y191244I1288J-190D01*
G03X248901I1302J0D01*
G03X248887Y191431I-1302J-3D01*
G02X249283Y191888I396J57D01*
G01X249514D01*
Y191658D01*
X249505Y191629D01*
G03X249447Y191244I1244J-384D01*
G03X252051I1302J0D01*
G03X252037Y191431I-1302J-3D01*
G02X252433Y191888I396J57D01*
G01X252663D01*
Y191658D01*
X252654Y191629D01*
G03X252596Y191244I1244J-384D01*
G03X255200I1302J0D01*
G03X255186Y191431I-1302J-3D01*
G02X255582Y191888I396J57D01*
G01X255813D01*
Y191658D01*
X255804Y191629D01*
G03X255746Y191244I1244J-384D01*
G03X258350I1302J0D01*
G03X258336Y191431I-1302J-3D01*
G02X258732Y191888I396J57D01*
G37*
G36*
G01X283454Y252418D02*
X288698D01*
X291188Y249927D01*
Y240189D01*
X286900Y235900D01*
Y235768D01*
X286863Y235716D01*
G03X286584Y234844I1223J-872D01*
G03X286900Y233922I1503J0D01*
G01Y223000D01*
X280426Y216526D01*
Y212274D01*
X273000Y204847D01*
X251530D01*
G03X249968I-781J-1043D01*
G01X248380D01*
G03X246818I-781J-1043D01*
G01X245231D01*
G03X243669I-781J-1043D01*
G01X235782D01*
G03X235001Y205107I-781J-1043D01*
G03X234786Y205089I1J-1302D01*
G01X234684Y205072D01*
X234217Y205539D01*
X234447Y205770D01*
X234566Y205728D01*
G03X235001Y205653I436J1227D01*
G03X236303Y206955I0J1302D01*
G03X235009Y208257I-1302J0D01*
G02X234612Y208657I3J400D01*
G01Y211988D01*
X238750D01*
G03X239319Y212131I-2J1211D01*
G01X239363Y212154D01*
X240603D01*
G03X241300Y211952I697J1100D01*
G03X241997Y212154I0J1302D01*
G01X246902D01*
G03X247599Y211952I697J1100D01*
G03X248296Y212154I0J1302D01*
G01X250052D01*
G03X250749Y211952I697J1100D01*
G03X251446Y212154I0J1302D01*
G01X253201D01*
G03X253898Y211952I697J1100D01*
G03X254595Y212154I0J1302D01*
G01X256351D01*
G03X257048Y211952I697J1100D01*
G03X258340Y213089I0J1303D01*
G01X258348Y213157D01*
X259358Y214167D01*
G02X260002Y214056I283J-283D01*
G03X261269Y213255I1267J602D01*
G03X262189Y213599I0J1402D01*
G02X262468Y213583I131J-151D01*
G03X263580Y213090I1113J1010D01*
G01X267080D01*
G03X268163Y213552I-1J1503D01*
G02X268443Y213560I144J-139D01*
G03X269391Y213191I948J1033D01*
G03Y215995I0J1402D01*
G03X268443Y215626I0J-1402D01*
G02X268163Y215634I-136J147D01*
G03X267080Y216096I-1084J-1041D01*
G01X263580D01*
G03X262526Y215663I1J-1502D01*
G02X262246I-140J143D01*
G03X261871Y215923I-976J-1007D01*
G02X261759Y216568I171J362D01*
G01X262746Y217554D01*
Y235133D01*
X265218Y237604D01*
G03X265480Y237997I-858J856D01*
G01X265610Y238310D01*
X276100Y248800D01*
X279836D01*
X283454Y252418D01*
G37*
G36*
G01X305853Y135383D02*
X316513D01*
X318641Y133255D01*
Y119087D01*
G02X318190Y118690I-400J0D01*
G03X318000Y118702I-189J-1490D01*
G03X316610Y117770I0J-1503D01*
G02X316001Y117602I-370J152D01*
G03X315100Y117902I-901J-1203D01*
G03Y114898I0J-1502D01*
G03X316490Y115830I0J1503D01*
G02X317099Y115998I370J-152D01*
G03X318000Y115698I901J1203D01*
G03X318190Y115710I1J1502D01*
G02X318641Y115313I51J-397D01*
G01Y107839D01*
X313078Y102276D01*
X302162D01*
G02X301887Y102967I0J400D01*
G03X302358Y104059I-1030J1092D01*
G03X299354I-1502J0D01*
G03X299373Y103822I1502J1D01*
G02X298893Y103368I-395J-63D01*
G03X298575Y103402I-318J-1468D01*
G03X297162Y102408I0J-1501D01*
G01X297114Y102276D01*
X293224D01*
X282190Y113310D01*
Y134263D01*
X283310Y135383D01*
X300486D01*
X300535Y135255D01*
G03X301936Y134295I1401J542D01*
G03X302968Y134706I0J1501D01*
G02X303494Y134727I275J-290D01*
G03X304436Y134395I942J1170D01*
G03X305799Y135267I0J1501D01*
G01X305853Y135383D01*
G37*
G36*
G01X303900Y253831D02*
X308024D01*
X309124Y252730D01*
Y252459D01*
X310871Y250712D01*
X311142D01*
X311300Y250555D01*
X323954D01*
X328290Y246219D01*
Y176485D01*
X325479Y173674D01*
G02X324815Y173835I-283J283D01*
G03X323384Y174880I-1431J-457D01*
G03X321882Y173378I0J-1502D01*
G03X321883Y173338I1502J18D01*
G02X321483Y172928I-400J-10D01*
G01X316219D01*
G02X315916Y173589I0J400D01*
G03X316232Y174439I-985J850D01*
G03X313628I-1302J0D01*
G03X313944Y173589I1301J0D01*
G02X313641Y172928I-303J-261D01*
G01X309466D01*
X309443Y173102D01*
G03X306861I-1291J-166D01*
G01X306838Y172928D01*
X306316D01*
X306293Y173102D01*
G03X303711I-1291J-166D01*
G01X303688Y172928D01*
X296724D01*
X296701Y173102D01*
G03X294119I-1291J-166D01*
G01X294096Y172928D01*
X293698D01*
X293675Y173102D01*
G03X291093I-1291J-166D01*
G01X291070Y172928D01*
X290559D01*
X290523Y173083D01*
G03X287985I-1269J-291D01*
G01X287949Y172928D01*
X287419D01*
X287396Y173102D01*
G03X286105Y174238I-1291J-166D01*
G03X284998Y173621I0J-1302D01*
G02X284375Y173548I-340J210D01*
G01X282416Y175507D01*
Y200016D01*
X285518Y203118D01*
X285640Y203072D01*
G03X286105Y202986I465J1216D01*
G03X287256Y203680I0J1301D01*
G02X287958Y203690I354J-187D01*
G03X289091Y203029I1133J641D01*
G03X290393Y204331I0J1302D01*
G03X289441Y205585I-1302J0D01*
G02X289266Y206253I108J385D01*
G01X291657Y208643D01*
G03X291963Y209162I-858J856D01*
G02X292188Y209303I192J-56D01*
G03X292404Y209285I216J1284D01*
G03X293706Y210587I0J1302D01*
G03X293620Y211052I-1302J0D01*
G01X293574Y211174D01*
X296999Y214599D01*
X297057Y214612D01*
G03X298201Y215756I-323J1467D01*
G01X298214Y215814D01*
X306200Y223800D01*
Y246100D01*
X302500Y249800D01*
Y252431D01*
X303900Y253831D01*
G37*
G36*
G01X295187Y461587D02*
X299678D01*
X300086Y461179D01*
Y448087D01*
X302598Y445575D01*
X329773D01*
X332404Y442944D01*
Y433340D01*
G03X332386Y432809I8235J-545D01*
G03X332404Y432278I8253J14D01*
G01Y429284D01*
X337355Y424333D01*
Y405955D01*
X336800Y405400D01*
X316400D01*
X314050Y407750D01*
Y430353D01*
X307981Y436422D01*
X296239D01*
X294749Y437912D01*
Y461149D01*
X295187Y461587D01*
G37*
G36*
G01X326958Y374484D02*
X333044D01*
X333809Y373719D01*
Y345826D01*
G03X333524Y345046I927J-781D01*
G01Y318244D01*
G03X333809Y317464I1212J1D01*
G01Y316628D01*
X343942Y306494D01*
Y126349D01*
X342135Y124541D01*
X327191D01*
X323790Y127942D01*
Y145608D01*
X329385Y151203D01*
X329434Y151217D01*
G03X330445Y152228I-429J1440D01*
G01X330459Y152277D01*
X331603Y153421D01*
X331665Y153432D01*
G03X332907Y154911I-260J1479D01*
G03X332889Y155141I-1502J-2D01*
G01X332887Y155156D01*
Y157166D01*
X332889Y157181D01*
G03X332907Y157411I-1484J232D01*
G03X332889Y157641I-1502J-2D01*
G01X332887Y157656D01*
Y159666D01*
X332889Y159681D01*
G03X332907Y159911I-1484J232D01*
G03X332889Y160141I-1502J-2D01*
G01X332887Y160156D01*
Y164666D01*
X332889Y164681D01*
G03X332907Y164911I-1484J232D01*
G03X332889Y165141I-1502J-2D01*
G01X332887Y165156D01*
Y167166D01*
X332889Y167181D01*
G03X332907Y167411I-1484J232D01*
G03X332889Y167641I-1502J-2D01*
G01X332887Y167656D01*
Y169666D01*
X332889Y169681D01*
G03X332907Y169911I-1484J232D01*
G03X332889Y170141I-1502J-2D01*
G01X332887Y170156D01*
Y172166D01*
X332889Y172181D01*
G03X332907Y172411I-1484J232D01*
G03X332889Y172641I-1502J-2D01*
G01X332887Y172656D01*
Y174666D01*
X332889Y174681D01*
G03X332907Y174911I-1484J232D01*
G03X332889Y175141I-1502J-2D01*
G01X332887Y175156D01*
Y177166D01*
X332889Y177181D01*
G03X332907Y177411I-1484J232D01*
G03X332889Y177641I-1502J-2D01*
G01X332887Y177656D01*
Y179666D01*
X332889Y179681D01*
G03X332907Y179911I-1484J232D01*
G03X332889Y180141I-1502J-2D01*
G01X332887Y180156D01*
Y182681D01*
X332889Y182696D01*
G03X332907Y182926I-1484J232D01*
G03X332889Y183156I-1502J-2D01*
G01X332887Y183171D01*
Y187166D01*
X332889Y187181D01*
G03X332907Y187411I-1484J232D01*
G03X332889Y187641I-1502J-2D01*
G01X332887Y187656D01*
Y189666D01*
X332889Y189681D01*
G03X332907Y189911I-1484J232D01*
G03X332889Y190141I-1502J-2D01*
G01X332887Y190156D01*
Y192166D01*
X332889Y192181D01*
G03X332907Y192411I-1484J232D01*
G03X332889Y192641I-1502J-2D01*
G01X332887Y192656D01*
Y194763D01*
X329798Y197852D01*
Y246430D01*
X324514Y251714D01*
X311286D01*
X310126Y252874D01*
Y270874D01*
X316152Y276900D01*
Y289891D01*
G02X316787Y290215I400J0D01*
G03X317670Y289928I883J1215D01*
G03X319172Y291430I0J1502D01*
G03X317700Y292932I-1502J0D01*
G02X317309Y293356I8J400D01*
G03X317312Y293450I-1499J95D01*
G03X317289Y293711I-1502J-1D01*
G02X317630Y294176I394J69D01*
G03X318932Y295665I-200J1489D01*
G03X317430Y297167I-1502J0D01*
G03X316737Y296997I1J-1502D01*
G02X316152Y297352I-185J355D01*
G01Y307052D01*
X315515Y307689D01*
X315501Y307716D01*
G03X314866Y308351I-1331J-696D01*
G01X314839Y308365D01*
X314569Y308635D01*
X314735Y308802D01*
X314767Y308817D01*
G03X315634Y310178I-635J1361D01*
G03X314132Y311680I-1502J0D01*
G01Y319868D01*
X312000Y322000D01*
X308500D01*
X307574Y322926D01*
Y339074D01*
X309220Y340720D01*
Y344242D01*
G03X309512Y345101I-1120J860D01*
G01Y348500D01*
G03X309220Y349359I-1412J-1D01*
G01Y358530D01*
X311018Y360328D01*
Y364642D01*
G02X311525Y365027I400J0D01*
G03X311925Y364973I399J1448D01*
G03X313175Y365643I0J1501D01*
G02X313838Y365648I333J-222D01*
G03X315075Y364998I1237J852D01*
G03Y368002I0J1502D01*
G03X313825Y367332I0J-1501D01*
G02X313162Y367327I-333J222D01*
G03X311925Y367977I-1237J-852D01*
G03X311525Y367923I-1J-1502D01*
G02X311018Y368308I-107J385D01*
G01Y373885D01*
X311617Y374484D01*
X325242D01*
G03X326958I858J1234D01*
G37*
G36*
G01X314385Y467812D02*
X315625D01*
X315966Y467471D01*
Y453751D01*
X315647Y453432D01*
X314431D01*
X313969Y453894D01*
Y467396D01*
X314385Y467812D01*
G37*
%LPC*%
G75*
G36*
G01X34677Y239385D02*
G03Y240015I-246J315D01*
G02X34098Y241200I923J1185D01*
G02X37102I1502J0D01*
G02X36523Y240015I-1502J0D01*
G03Y239385I246J-315D01*
G02X37102Y238200I-923J-1185D01*
G02X34098I-1502J0D01*
G02X34677Y239385I1502J0D01*
G37*
G36*
G01X38105Y302475D02*
G03Y303102I-249J314D01*
G02X37537Y304278I933J1176D01*
G02X40541I1502J0D01*
G02X39973Y303102I-1501J0D01*
G03Y302475I249J-313D01*
G02X40541Y301299I-933J-1176D01*
G02X37537I-1502J0D01*
G02X38105Y302475I1501J0D01*
G37*
G36*
G01X29956Y303264D02*
G02X29136Y304602I682J1338D01*
G02X32140I1502J0D01*
G02X31320Y303264I-1502J0D01*
G03Y302551I182J-357D01*
G02X32140Y301213I-682J-1338D01*
G02X29136I-1502J0D01*
G02X29956Y302551I1502J0D01*
G03Y303264I-182J356D01*
G37*
G36*
G01X21555Y303288D02*
G02X20735Y304626I682J1338D01*
G02X23739I1502J0D01*
G02X22919Y303288I-1502J0D01*
G03Y302575I182J-357D01*
G02X23739Y301237I-682J-1338D01*
G02X20735I-1502J0D01*
G02X21555Y302575I1502J0D01*
G03Y303288I-182J357D01*
G37*
G36*
G01X218412Y285320D02*
G03X218493Y285865I-246J315D01*
G02X218220Y286728I1229J863D01*
G02X221224I1502J0D01*
G02X220649Y285546I-1502J0D01*
G03X220568Y285001I246J-315D01*
G02X220841Y284138I-1229J-863D01*
G02X220459Y283137I-1503J0D01*
G03X220463Y282599I298J-267D01*
G02X220861Y281580I-1104J-1019D01*
G02X217857I-1502J0D01*
G02X218239Y282581I1503J0D01*
G03X218235Y283119I-298J267D01*
G02X217837Y284138I1104J1019D01*
G02X218412Y285320I1502J0D01*
G37*
G36*
G01X261260Y208349D02*
G03X261540Y208346I142J142D01*
G02X262580Y208764I1040J-1085D01*
G01X266080D01*
G02X267163Y208303I0J-1503D01*
G03X267443Y208295I144J139D01*
G02X268391Y208664I948J-1033D01*
G02Y205860I0J-1402D01*
G02X267443Y206229I0J1402D01*
G03X267163Y206221I-136J-147D01*
G02X266080Y205760I-1083J1042D01*
G01X262580D01*
G02X261454Y206267I-1J1502D01*
G03X261175Y206288I-150J-132D01*
G02X260269Y205956I-906J1070D01*
G02Y208760I0J1402D01*
G02X261260Y208349I-1J-1402D01*
G37*
G36*
G01X281496Y234122D02*
G03X280970I-263J-302D01*
G02X279983Y233752I-987J1131D01*
G02Y236756I0J1502D01*
G02X280970Y236386I0J-1501D01*
G03X281496I263J302D01*
G02X282483Y236756I987J-1131D01*
G02Y233752I0J-1502D01*
G02X281496Y234122I0J1501D01*
G37*
G36*
G01X299082Y120398D02*
G03X299508Y120843I29J399D01*
G02X299498Y121016I1491J173D01*
G02X301000Y119514I1502J0D01*
G02X300893Y119518I3J1502D01*
G03X300467Y119073I-29J-399D01*
G02X300477Y118900I-1491J-173D01*
G02X298975Y120402I-1502J0D01*
G02X299082Y120398I-3J-1502D01*
G37*
G36*
G01X306549Y127389D02*
G02X306058Y128500I1011J1111D01*
G02X309062I1502J0D01*
G02X308524Y127348I-1502J0D01*
G03X308511Y126746I257J-307D01*
G02X309002Y125635I-1011J-1111D01*
G02X308182Y124297I-1502J0D01*
G03X308161Y123595I181J-357D01*
G02X308902Y122300I-761J-1295D01*
G02X305898I-1502J0D01*
G02X306718Y123638I1502J0D01*
G03X306739Y124340I-181J357D01*
G02X305998Y125635I761J1295D01*
G02X306536Y126787I1502J0D01*
G03X306549Y127389I-257J307D01*
G37*
G36*
G01X288202Y130096D02*
G02X287796Y130040I-406J1446D01*
G02X289298Y131542I0J1502D01*
G02X289289Y131376I-1502J-2D01*
G03X289794Y130946I397J-45D01*
G02X290200Y131002I406J-1446D01*
G02X288698Y129500I0J-1502D01*
G02X288707Y129666I1502J2D01*
G03X288202Y130096I-397J45D01*
G37*
G36*
G01X318768Y199439D02*
G03X318672Y199959I-343J206D01*
G02X318099Y201140I929J1180D01*
G02X321103I1502J0D01*
G02X320887Y200364I-1502J0D01*
G03X320983Y199844I343J-206D01*
G02X321556Y198663I-929J-1180D01*
G02X318552I-1502J0D01*
G02X318768Y199439I1502J0D01*
G37*
G36*
G01X303752Y210950D02*
G03X303502Y211438I-384J111D01*
G02X302638Y212664I438J1226D01*
G02X305242I1302J0D01*
G02X305190Y212301I-1302J1D01*
G03X305440Y211813I384J-111D01*
G02X306304Y210587I-438J-1226D01*
G02X303700I-1302J0D01*
G02X303752Y210950I1302J-1D01*
G37*
G36*
G01X296072Y196543D02*
G02X296070Y196616I1300J72D01*
G02X297372Y195314I1302J0D01*
G02X297171Y195330I2J1302D01*
G03X296710Y194912I-62J-395D01*
G02X296712Y194839I-1300J-72D01*
G02X295410Y196141I-1302J0D01*
G02X295611Y196125I-2J-1302D01*
G03X296072Y196543I62J395D01*
G37*
G36*
G01X291753Y196818D02*
G02X291059Y197970I609J1152D01*
G02X293663I1302J0D01*
G02X293002Y196836I-1303J0D01*
G03X293012Y196135I197J-348D01*
G02X293706Y194983I-609J-1152D01*
G02X291102I-1302J0D01*
G02X291763Y196117I1303J0D01*
G03X291753Y196818I-197J348D01*
G37*
G36*
G01X309367Y213244D02*
G02X308460Y212876I-907J934D01*
G02Y215480I0J1302D01*
G02X309617Y214775I0J-1302D01*
G03X310251Y214671I356J183D01*
G02X311158Y215039I907J-934D01*
G02Y212435I0J-1302D01*
G02X310001Y213140I0J1302D01*
G03X309367Y213244I-356J-183D01*
G37*
G36*
G01X305974Y220635D02*
G03X306500I263J302D01*
G02X307487Y221005I987J-1131D01*
G02X308907Y219992I0J-1502D01*
G03X309530Y219805I378J130D01*
G02X310449Y220119I919J-1188D01*
G02Y217115I0J-1502D01*
G02X309029Y218128I0J1502D01*
G03X308406Y218315I-378J-130D01*
G02X307487Y218001I-919J1188D01*
G02X306500Y218371I0J1501D01*
G03X305974I-263J-302D01*
G02X304987Y218001I-987J1131D01*
G02Y221005I0J1502D01*
G02X305974Y220635I0J-1501D01*
G37*
G36*
G01X325641Y228400D02*
G02X324821Y229738I682J1338D01*
G02X327825I1502J0D01*
G02X327005Y228400I-1502J0D01*
G03Y227687I182J-357D01*
G02X327825Y226349I-682J-1338D01*
G02X324821I-1502J0D01*
G02X325641Y227687I1502J0D01*
G03Y228400I-182J357D01*
G37*
G36*
G01X317240Y228424D02*
G02X316420Y229762I682J1338D01*
G02X319424I1502J0D01*
G02X318604Y228424I-1502J0D01*
G03Y227711I182J-357D01*
G02X319424Y226373I-682J-1338D01*
G02X316420I-1502J0D01*
G02X317240Y227711I1502J0D01*
G03Y228424I-182J357D01*
G37*
G36*
G01X308839Y228448D02*
G02X308019Y229786I682J1338D01*
G02X311023I1502J0D01*
G02X310203Y228448I-1502J0D01*
G03Y227735I182J-357D01*
G02X311023Y226397I-682J-1338D01*
G02X308019I-1502J0D01*
G02X308839Y227735I1502J0D01*
G03Y228448I-182J357D01*
G37*
G36*
G01X325641Y237355D02*
G02X324821Y238693I682J1338D01*
G02X327825I1502J0D01*
G02X327005Y237355I-1502J0D01*
G03Y236642I182J-357D01*
G02X327825Y235304I-682J-1338D01*
G02X324821I-1502J0D01*
G02X325641Y236642I1502J0D01*
G03Y237355I-182J357D01*
G37*
G36*
G01X317240Y237379D02*
G02X316420Y238717I682J1338D01*
G02X319424I1502J0D01*
G02X318604Y237379I-1502J0D01*
G03Y236666I182J-357D01*
G02X319424Y235328I-682J-1338D01*
G02X316420I-1502J0D01*
G02X317240Y236666I1502J0D01*
G03Y237379I-182J357D01*
G37*
G36*
G01X308839Y237403D02*
G02X308019Y238741I682J1338D01*
G02X311023I1502J0D01*
G02X310203Y237403I-1502J0D01*
G03Y236690I182J-357D01*
G02X311023Y235352I-682J-1338D01*
G02X308019I-1502J0D01*
G02X308839Y236690I1502J0D01*
G03Y237403I-182J357D01*
G37*
G36*
G01X338620Y153254D02*
G03X338711Y153876I-199J347D01*
G02X338298Y154911I1090J1035D01*
G02X341302I1502J0D01*
G02X340549Y153609I-1502J0D01*
G03X340458Y152987I199J-347D01*
G02X340871Y151952I-1090J-1035D01*
G02X337867I-1502J0D01*
G02X338620Y153254I1502J0D01*
G37*
G36*
G01X338963Y164053D02*
G03X338934Y164684I-260J304D01*
G02X338298Y165911I866J1227D01*
G02X341302I1502J0D01*
G02X340776Y164769I-1503J0D01*
G03X340805Y164138I260J-304D01*
G02Y161684I-866J-1227D01*
G03X340776Y161053I231J-327D01*
G02X341302Y159911I-977J-1142D01*
G02X338298I-1502J0D01*
G02X338934Y161138I1502J0D01*
G03X338963Y161769I-231J327D01*
G02Y164053I977J1142D01*
G37*
G36*
G01X338728Y294145D02*
G03Y294755I-259J305D01*
G02X338198Y295900I972J1145D01*
G02X341202I1502J0D01*
G02X340672Y294755I-1502J0D01*
G03Y294145I259J-305D01*
G02X341202Y293000I-972J-1145D01*
G02X338198I-1502J0D01*
G02X338728Y294145I1502J0D01*
G37*
G36*
G01X323911Y327035D02*
G03Y327581I-292J273D01*
G02X323505Y328608I1096J1027D01*
G02X325007Y330110I1502J0D01*
G02X326061Y329678I0J-1502D01*
G03X326628Y329683I281J285D01*
G02X327704Y330137I1076J-1048D01*
G02X329206Y328635I0J-1502D01*
G02X328800Y327608I-1502J0D01*
G03Y327062I292J-273D01*
G02X329206Y326035I-1096J-1027D01*
G02X328836Y325048I-1501J0D01*
G03Y324522I302J-263D01*
G02X329206Y323535I-1131J-987D01*
G02X327704Y322033I-1502J0D01*
G02X326650Y322465I0J1502D01*
G03X326083Y322460I-281J-285D01*
G02X325007Y322006I-1076J1048D01*
G02X323505Y323508I0J1502D01*
G02X323875Y324495I1501J0D01*
G03Y325021I-302J263D01*
G02X323505Y326008I1131J987D01*
G02X323911Y327035I1502J0D01*
G37*
G36*
G01X338869Y184732D02*
G02X338298Y185911I932J1179D01*
G02X341302I1502J0D01*
G02X340731Y184732I-1503J0D01*
G03Y184105I248J-314D01*
G02X341302Y182926I-932J-1179D01*
G02X340716Y181736I-1501J0D01*
G03Y181101I244J-317D01*
G02X341302Y179911I-915J-1190D01*
G02X340723Y178726I-1502J0D01*
G03Y178096I246J-315D01*
G02X341302Y176911I-923J-1185D01*
G02X338298I-1502J0D01*
G02X338877Y178096I1502J0D01*
G03Y178726I-246J315D01*
G02X338298Y179911I923J1185D01*
G02X338884Y181101I1501J0D01*
G03Y181736I-244J317D01*
G02X338298Y182926I915J1190D01*
G02X338869Y184105I1503J0D01*
G03Y184732I-248J313D01*
G37*
G36*
G01X334041Y228400D02*
G02X333221Y229738I682J1338D01*
G02X336225I1502J0D01*
G02X335405Y228400I-1502J0D01*
G03Y227687I182J-357D01*
G02X336225Y226349I-682J-1338D01*
G02X333221I-1502J0D01*
G02X334041Y227687I1502J0D01*
G03Y228400I-182J357D01*
G37*
G36*
G01X334042Y237331D02*
G02X333222Y238669I682J1338D01*
G02X334724Y240171I1502J0D01*
G02X336226Y238685I0J-1502D01*
G03X336803Y238331I400J5D01*
G02X337467Y238486I664J-1347D01*
G02Y235482I0J-1502D01*
G02X336803Y235637I0J1502D01*
G03X336226Y235278I-177J-359D01*
G02X334724Y233778I-1502J2D01*
G02X333222Y235280I0J1502D01*
G02X334042Y236618I1502J0D01*
G03Y237331I-182J357D01*
G37*
G36*
G01X335532Y285069D02*
G02X334810Y286352I779J1283D01*
G02X337814I1502J0D01*
G02X337210Y285148I-1502J0D01*
G03X337241Y284485I239J-321D01*
G02X337963Y283202I-779J-1283D01*
G02X334959I-1502J0D01*
G02X335563Y284406I1502J0D01*
G03X335532Y285069I-239J321D01*
G37*
G54D17*
X39408Y195990D03*
X19100Y187420D03*
X24705Y258767D03*
X37485Y258807D03*
X41100Y248900D03*
X86700Y119100D03*
X78700Y340000D03*
X71700Y340600D03*
X90500Y397600D03*
X82500D03*
X86300D03*
X220866Y272160D03*
X217500Y264000D03*
X219900Y267100D03*
X191583Y261363D03*
X195370Y273297D03*
X189228Y280655D03*
X185897Y249936D03*
X190900Y271700D03*
X187400Y255700D03*
X200680Y257540D03*
X198990Y247811D03*
X196827Y240349D03*
X265226Y164982D03*
X269133D03*
X268339Y222126D03*
X286000Y242100D03*
X301000Y129900D03*
X285250Y117250D03*
X294200Y128800D03*
X294800Y111800D03*
X294600Y106900D03*
X288116Y120306D03*
X313800Y124300D03*
X301151Y108649D03*
X295075Y119100D03*
X288280Y126212D03*
X300500Y125000D03*
X304000Y116500D03*
X323384Y177378D03*
X320054Y195163D03*
X317110Y219140D03*
X329297Y134594D03*
X337842Y128533D03*
X339800Y169911D03*
Y189911D03*
X331741Y138243D03*
X331641Y141743D03*
X333278Y151129D03*
X329297Y129890D03*
X325038Y356890D03*
X337004Y202113D03*
Y206113D03*
Y210113D03*
X337083Y197000D03*
X339812Y173380D03*
X337400Y193449D03*
X328087Y141608D03*
X327162Y278972D03*
X312300Y340700D03*
X326200Y370681D03*
X325900Y365643D03*
X329925Y356016D03*
X330900Y314700D03*
G54D18*
X87617Y365322D03*
Y371584D03*
X71906Y349574D03*
X78206D03*
X71906Y352724D03*
X75056Y355873D03*
Y352724D03*
X71906Y355873D03*
Y359023D03*
X78206Y365322D03*
X81355D03*
X75056D03*
Y362173D03*
X78206Y371584D03*
Y374733D03*
X81355Y371584D03*
X71906Y362173D03*
Y365322D03*
X75056Y359023D03*
X78206Y362173D03*
X81355D03*
X75056Y346425D03*
Y349574D03*
X78206Y359023D03*
X92360Y394175D03*
X71906Y387332D03*
X81355D03*
X89210Y394175D03*
X87617Y390481D03*
X93916Y387332D03*
X90766D03*
Y390481D03*
X87617Y387332D03*
X212991Y219553D03*
X216141Y222703D03*
X216103Y219591D03*
X197243Y219553D03*
X200393Y213254D03*
X194094Y229002D03*
X203542D03*
X206692Y225852D03*
X203542D03*
Y232151D03*
X197243Y235301D03*
X200393Y232151D03*
X250749Y188095D03*
X247599Y181795D03*
X253898Y184945D03*
Y178646D03*
X247599Y184945D03*
X250749Y181795D03*
Y178646D03*
X247599D03*
X250749Y184945D03*
X247599Y188095D03*
X244450D03*
X241300D03*
X244450Y181795D03*
Y175496D03*
Y184945D03*
Y178646D03*
X241300Y184945D03*
Y178646D03*
Y175496D03*
X253898Y206955D03*
X247599D03*
Y210104D03*
X250749Y206955D03*
X257048D03*
X250749Y210104D03*
X241300D03*
X311158Y185534D03*
X311301Y182385D03*
X314930Y177588D03*
X308152Y176085D03*
Y182385D03*
X308008Y185391D03*
X308152Y179235D03*
X314930Y180738D03*
X314307Y185534D03*
Y191690D03*
X308008D03*
X311158D03*
X308008Y188540D03*
X311158D03*
X292404Y185534D03*
Y176085D03*
X305002D03*
X295410Y179235D03*
X305002D03*
X295411Y185534D03*
X292260Y179235D03*
X292404Y191690D03*
X286105Y182385D03*
X289254Y176085D03*
Y182385D03*
X289111Y179235D03*
X289254Y185534D03*
X286105D03*
X285482Y190187D03*
X289254Y191690D03*
X311158Y204288D03*
X314307Y207438D03*
X308008D03*
X308152Y204432D03*
X311158Y210587D03*
X308008Y210731D03*
X314307Y204288D03*
Y210587D03*
Y213737D03*
X298714Y210477D03*
X305002Y204432D03*
X295410Y210587D03*
X286105Y201139D03*
Y197989D03*
X289254Y194839D03*
X292404Y201282D03*
X289254Y201139D03*
Y197989D03*
X286105Y194839D03*
X299667Y201334D03*
X311158Y201139D03*
Y194839D03*
X308008Y198133D03*
X314307Y201139D03*
X311158Y197989D03*
X314307Y194839D03*
X308008D03*
X314307Y197989D03*
G54D19*
X79000Y395500D03*
X203542Y213254D03*
X301507Y195435D03*
%LPD*%
G75*
G54D10*
X-61100Y250316D03*
X-51100D03*
G54D11*
G01X271990Y362360D02*
X275650D01*
X282520Y355490D01*
Y339471D01*
X285860Y336131D01*
X3000Y8494D03*
Y28494D03*
Y48494D03*
Y68494D03*
Y88494D03*
Y108494D03*
Y128494D03*
Y148494D03*
Y168494D03*
Y188494D03*
Y208494D03*
Y228494D03*
Y248494D03*
Y268494D03*
Y288494D03*
Y308494D03*
Y342126D03*
Y362126D03*
Y382126D03*
Y402126D03*
Y422126D03*
Y442126D03*
X16626Y195848D03*
X19129D03*
Y193048D03*
X16626D03*
X19129Y204248D03*
X17000Y208017D03*
Y211541D03*
X16626Y198648D03*
Y201448D03*
X19129Y198648D03*
Y201448D03*
X16626Y204248D03*
X17000Y215713D03*
Y219288D03*
X18000Y240900D03*
Y237900D03*
Y249900D03*
Y246900D03*
Y243900D03*
X13827Y325310D03*
X22218Y3000D03*
X31890Y110400D03*
X31920Y186610D03*
X21250Y206220D03*
X21135Y236587D03*
X21205Y232767D03*
X21135Y240667D03*
Y243737D03*
X24690Y246467D03*
Y251967D03*
X21135Y246837D03*
X21035Y249937D03*
X24690Y249267D03*
X22237Y311481D03*
Y308592D03*
X30638Y311957D03*
Y309068D03*
X33000Y318700D03*
X31000Y342500D03*
X25202Y425329D03*
X20225Y447671D03*
X22692Y466518D03*
X42218Y3000D03*
X45500Y92500D03*
X40340Y100710D03*
X47294Y184491D03*
X36599Y189016D03*
X37360Y194050D03*
X37823Y198346D03*
X39567Y243133D03*
X40500Y236900D03*
X41574Y255937D03*
X39039Y309044D03*
Y311933D03*
X50950Y318050D03*
X43500Y317100D03*
X48420Y321616D03*
X44481Y328760D03*
X35500Y335000D03*
X44525Y360000D03*
X35100Y352400D03*
X37300Y375000D03*
X37735Y391200D03*
X37020Y385600D03*
X44500Y380000D03*
X44330Y401450D03*
X42200Y435900D03*
X38000Y428800D03*
X40848Y448440D03*
X62218Y3000D03*
X59240Y67242D03*
X61123Y133070D03*
X59700Y196200D03*
X59850Y235830D03*
X50567Y238630D03*
X64230Y303210D03*
X52800Y322400D03*
X57400Y345400D03*
X54400Y374700D03*
X68500Y66500D03*
X75280Y75704D03*
X72044Y132312D03*
X71970Y135893D03*
X69195Y135799D03*
X69285Y132321D03*
X68335Y141369D03*
X68375Y144100D03*
X68434Y149506D03*
X68432Y152147D03*
X76442Y166907D03*
X74046Y186490D03*
X71600Y200900D03*
X72150Y204810D03*
X76670Y208772D03*
X74583Y217314D03*
X73011Y246365D03*
X77437Y262760D03*
X78770Y290708D03*
X75300Y305150D03*
X76500Y325500D03*
X67900Y400525D03*
X73976Y408665D03*
X69030Y422653D03*
X82218Y3000D03*
X88500Y128000D03*
X86100Y153340D03*
Y155840D03*
Y158390D03*
X81500Y176515D03*
X82370Y197010D03*
X91300Y252900D03*
X81864Y297900D03*
X85600Y298100D03*
X82200Y308700D03*
X82022Y303350D03*
X84126Y311790D03*
X79600Y312000D03*
X92698Y323224D03*
X89487Y408435D03*
X84801Y409760D03*
X84320Y430510D03*
X92870Y437831D03*
X102218Y3000D03*
X98720Y236980D03*
X106574Y280028D03*
X100700Y293600D03*
X99990Y311200D03*
X105100Y309300D03*
X100500Y328547D03*
X103000Y323800D03*
X99026Y338368D03*
X103180Y336286D03*
X100457Y409100D03*
X109048Y425853D03*
X95845Y424755D03*
X95770Y437920D03*
X103900Y447640D03*
X122218Y3000D03*
X109670Y136060D03*
X113000Y160700D03*
X123120Y213088D03*
X112200Y234520D03*
X119105Y251511D03*
X111600Y284000D03*
X120600Y293471D03*
X124935Y324900D03*
X115535Y335235D03*
X124300Y348800D03*
X111330Y357800D03*
X114700Y348500D03*
X125650Y368650D03*
X119200Y389700D03*
X110900Y378500D03*
X122600Y394600D03*
X122498Y419675D03*
X111510Y434710D03*
X121700Y424005D03*
X123170Y433200D03*
X140730Y72600D03*
X129300Y82650D03*
X131470Y81260D03*
X131528Y114271D03*
X135500Y138000D03*
Y135000D03*
X134400Y127652D03*
X133690Y158100D03*
X136190D03*
X137900Y179160D03*
X135300Y175100D03*
X126153Y199079D03*
X134358Y230069D03*
X137196Y274491D03*
X132420Y273811D03*
X124100Y311100D03*
X132600Y350090D03*
X138700Y376600D03*
X135300Y399900D03*
X137900Y399500D03*
X128866Y433066D03*
X135350Y433016D03*
X124500Y424005D03*
X133572Y423935D03*
X142218Y3000D03*
X145100Y87400D03*
X141220Y123070D03*
X146300Y161010D03*
X146882Y177501D03*
X140830Y192530D03*
X153051Y187354D03*
X144280Y195130D03*
X147800Y200789D03*
X146390Y224040D03*
X146000Y216350D03*
X141954Y224274D03*
X142300Y216300D03*
X153100Y234800D03*
X149862Y243788D03*
X145250Y256890D03*
X145580Y248082D03*
X141280Y256310D03*
X149215Y267745D03*
X147500Y289405D03*
X141890Y310570D03*
X142300Y336700D03*
X141000Y358500D03*
X152100Y378400D03*
X152500Y382600D03*
X150820Y387325D03*
X143000Y414600D03*
X145365Y426050D03*
X148060Y423500D03*
X138987Y423935D03*
X162218Y3000D03*
X158246Y78872D03*
X156710Y73420D03*
X162657Y117297D03*
X166700Y132360D03*
X162419Y131032D03*
X161900Y150500D03*
X161237Y181735D03*
X162653Y218843D03*
X159643Y226484D03*
X165500Y236100D03*
X158750Y284949D03*
X156300Y376300D03*
X165500Y386000D03*
X165501Y382800D03*
X158200Y381400D03*
X155452Y401000D03*
X162100Y414000D03*
X163700Y422119D03*
X160700Y445550D03*
X158100Y442700D03*
X182218Y3000D03*
X178200Y76145D03*
X175700Y76245D03*
X182108Y129094D03*
X176550Y125210D03*
X178284Y132394D03*
X170610Y131900D03*
X171700Y156900D03*
X169500Y180200D03*
X173800Y225400D03*
X172400Y220700D03*
X175300Y240000D03*
X174232Y304333D03*
X176533Y314049D03*
X181050Y332250D03*
X177500Y369100D03*
X187700Y99000D03*
X190744Y114456D03*
X196577Y141185D03*
X193084Y257400D03*
X194567Y255288D03*
X196200Y278200D03*
X196100Y281820D03*
X192380Y291900D03*
X194600Y313300D03*
X197853Y307200D03*
X188546Y326356D03*
X197775Y346617D03*
X197450Y356560D03*
X197711Y349250D03*
X195000Y373900D03*
X187400Y379400D03*
X197620Y385425D03*
X189054Y397500D03*
X194500Y402600D03*
X197600Y415400D03*
X190270Y409962D03*
X185000Y456500D03*
X202218Y3000D03*
X204300Y60600D03*
X201500Y61000D03*
X199985Y132294D03*
X212727Y129654D03*
X208627Y132394D03*
X208576Y128957D03*
X212727Y132154D03*
X205598Y140480D03*
X206200Y255385D03*
X201000Y262500D03*
X205900Y266130D03*
X204560Y301130D03*
X212911Y293869D03*
X206430Y298780D03*
X199729Y314565D03*
X208628Y324665D03*
X208565Y404501D03*
X200000Y407040D03*
X207278Y416022D03*
X198405Y434800D03*
X222218Y3000D03*
X224958Y107236D03*
X226040Y101220D03*
X226887Y117297D03*
X221278Y129294D03*
X225284D03*
X221278Y132294D03*
X227232Y270539D03*
X226405Y266335D03*
X222833Y261668D03*
X229220Y283250D03*
X217300Y322800D03*
X216405Y335970D03*
X213490Y373690D03*
X222575Y387625D03*
X227206Y400100D03*
X222986Y400323D03*
X220134Y400780D03*
X213900Y436000D03*
X224000Y449100D03*
X242218Y3000D03*
X232150Y82480D03*
X235630Y104990D03*
X232325Y101230D03*
X234500Y117500D03*
X239206Y112300D03*
X229396Y132294D03*
X242500Y129000D03*
X230535Y244564D03*
X237730Y248085D03*
X229630Y264404D03*
X231900Y272700D03*
X241188Y279347D03*
X235400Y303800D03*
X242592Y330683D03*
X235000Y335300D03*
X230287Y373100D03*
X233790Y384490D03*
X236670Y394550D03*
X241231Y407285D03*
X236860Y407300D03*
X231400Y449500D03*
X240010Y456000D03*
X240210Y453400D03*
X231400Y452000D03*
X253000Y77500D03*
X257800Y82800D03*
X247689Y247929D03*
X253110Y254909D03*
X253100Y257800D03*
X250288Y273581D03*
X258100Y295080D03*
X254355Y300577D03*
X247923Y316400D03*
X245900Y305000D03*
X248900Y304900D03*
X252350Y412850D03*
X246500Y448500D03*
X243375Y448375D03*
X262218Y3000D03*
X272505Y83545D03*
X260050Y87026D03*
X260200Y132395D03*
X265942Y150799D03*
X269004Y144450D03*
Y141950D03*
X259500Y263700D03*
X262730Y267600D03*
X258000Y284900D03*
X271990Y362360D03*
X271500Y418300D03*
X282218Y3000D03*
X279800Y72700D03*
X287578Y84092D03*
X283500Y89500D03*
X277505Y83545D03*
X282505D03*
X283500Y126000D03*
X283974Y251372D03*
X286800Y251400D03*
X282911Y279569D03*
X285911D03*
X287507Y301596D03*
X287050Y305850D03*
X289939Y309060D03*
X276660Y316900D03*
X286372Y320700D03*
X289600Y322253D03*
X286372Y326768D03*
X285860Y336131D03*
X276145Y366455D03*
X283664Y379236D03*
X278409Y433722D03*
X302218Y3000D03*
X291000Y297700D03*
X291300Y315900D03*
X290120Y339370D03*
X290000Y335600D03*
X300700Y341300D03*
X295729Y453912D03*
Y456912D03*
Y459912D03*
X297738Y452418D03*
Y458418D03*
Y455418D03*
X316066Y108407D03*
X315900Y125900D03*
X305000Y252400D03*
X307600Y252300D03*
X302879Y282487D03*
X309700Y294789D03*
X314340Y373296D03*
X314969Y456527D03*
X322218Y3000D03*
X331741Y125796D03*
X326932Y205685D03*
X326733Y209885D03*
X321045Y210257D03*
X320937Y212839D03*
X326733Y201485D03*
X326731Y213648D03*
X320931Y215387D03*
X325593Y406500D03*
X329093D03*
X318593D03*
X322093D03*
X331646Y466536D03*
X342218Y3000D03*
X342200Y100500D03*
X342180Y106900D03*
X340612Y278972D03*
X342604Y318773D03*
X345500Y342690D03*
X334112Y447668D03*
X351331Y20788D03*
Y40788D03*
Y60788D03*
Y80788D03*
Y100788D03*
Y120788D03*
Y140788D03*
Y160788D03*
Y180788D03*
Y200788D03*
Y220788D03*
Y240788D03*
Y260788D03*
Y280788D03*
Y300788D03*
X349290Y337646D03*
X351331Y357531D03*
Y377531D03*
Y397531D03*
Y417531D03*
Y437531D03*
G54D12*
G01X61123Y133070D02*
X61502D01*
X63302Y134870D01*
Y159665D01*
X61590Y161377D01*
Y179619D01*
X56830Y184379D01*
Y193330D01*
X59700Y196200D01*
G01D02*
X55448Y200452D01*
Y201736D01*
X54641Y202543D01*
Y211885D01*
X53790Y212736D01*
Y227345D01*
X55099Y228654D01*
X55100Y232460D01*
X54110Y233450D01*
Y235390D01*
X50870Y238630D01*
X50567D01*
G01X75280Y75704D02*
Y75279D01*
X68500Y68499D01*
Y66500D01*
G01X131528Y114271D02*
X126060Y119739D01*
X111903D01*
X109468Y122174D01*
X107478D01*
X106204Y120900D01*
X102529D01*
X96846Y126583D01*
Y129355D01*
X93104Y133097D01*
Y143772D01*
X86100Y150776D01*
Y153340D01*
G01Y155840D02*
Y153340D01*
G01Y158390D02*
Y155840D01*
G01X204560Y301130D02*
X204720Y301290D01*
Y302216D01*
X205100Y302596D01*
Y375583D01*
X205640Y376887D01*
X204352Y383356D01*
X202283Y385425D01*
X197620D01*
G01X279800Y72700D02*
Y75200D01*
X285025Y80425D01*
Y85075D01*
X283600Y86500D01*
X282100D01*
X280600Y88000D01*
Y91500D01*
X283750Y94650D01*
Y103650D01*
X273300Y114100D01*
X272052D01*
X265818Y120334D01*
Y122650D01*
X266800Y123632D01*
Y131900D01*
X268846Y133946D01*
Y135554D01*
X266800Y137600D01*
Y139100D01*
X264200Y141700D01*
Y147000D01*
X265942Y148742D01*
Y150799D01*
X68757Y374733D03*
X78206Y381033D03*
X71906Y384182D03*
X87617Y352724D03*
X90766Y349574D03*
X93916Y352724D03*
X81355Y355873D03*
X90766Y352724D03*
X81355Y374733D03*
X87617D03*
X103365Y346425D03*
X93916Y349574D03*
X97066Y384182D03*
X181495Y153449D03*
Y197506D03*
Y188095D03*
X178346D03*
Y203805D03*
X171836Y200655D03*
Y198300D03*
X178346Y229002D03*
X184645D03*
X187794Y153449D03*
X192400Y152804D03*
X184645Y153449D03*
Y156599D03*
X187794Y162898D03*
Y166047D03*
X184645Y162898D03*
Y159748D03*
X190944Y162898D03*
Y159748D03*
X194094Y166047D03*
X184645Y210104D03*
Y200655D03*
X200393Y222703D03*
X197243Y225852D03*
X184645Y213254D03*
X206692Y156599D03*
Y159748D03*
X200393Y219553D03*
X203542Y222703D03*
X209842Y232151D03*
X212991D03*
X209842Y229002D03*
X225658Y153369D03*
X228702Y229002D03*
X225590Y225852D03*
X219290Y222703D03*
X235001Y153449D03*
X228702Y162898D03*
X235001Y156599D03*
X241300Y159748D03*
X235001Y210104D03*
X235038Y225890D03*
X231889D03*
X247637Y162898D03*
X247599Y166047D03*
X244450Y169197D03*
Y191244D03*
X286105Y176085D03*
G54D13*
G01X184645Y210104D02*
X182845Y211904D01*
Y212507D01*
X179695Y215657D01*
Y221005D01*
X176200Y224500D01*
Y226250D01*
X175582Y226868D01*
X174048Y227504D01*
X173396Y228156D01*
Y231096D01*
X176420Y234120D01*
Y235910D01*
X173200Y239130D01*
Y240871D01*
X176634Y244305D01*
Y259414D01*
X178590Y261370D01*
Y265140D01*
X174800Y268930D01*
Y272000D01*
X177117Y274317D01*
Y301448D01*
X174232Y304333D01*
G01X236860Y407300D02*
X239815Y410255D01*
X241231D01*
X245700Y405786D01*
Y399428D01*
X243874Y397602D01*
Y383926D01*
X248750Y379050D01*
Y334829D01*
X248970Y334609D01*
Y334433D01*
X249543Y333860D01*
Y323557D01*
X252200Y320900D01*
Y295300D01*
X257798Y289702D01*
X260200Y286107D01*
Y283300D01*
X259200Y282300D01*
X255900D01*
X250288Y276688D01*
Y273581D01*
G54D14*
G01X166700Y132360D02*
X164670Y130330D01*
Y129840D01*
X161530Y126700D01*
Y124770D01*
X159310Y122550D01*
X153630D01*
X151660Y124520D01*
Y127070D01*
X150160Y128570D01*
X146860D01*
X141360Y123070D01*
X141220D01*
G01X147800Y200789D02*
Y203500D01*
X140800Y210500D01*
Y214300D01*
X138800Y216300D01*
Y217800D01*
X139900Y218900D01*
Y223100D01*
X139300Y223700D01*
Y232400D01*
X141880Y234980D01*
Y252142D01*
X145250Y255512D01*
Y256890D01*
G01X163700Y422119D02*
Y421200D01*
X177100Y407800D01*
Y395700D01*
X174600Y393200D01*
Y382900D01*
X185920Y371580D01*
Y355920D01*
X179950Y349950D01*
Y333350D01*
X181050Y332250D01*
G01X195000Y373900D02*
Y382805D01*
X197620Y385425D01*
G54D15*
G01X2010999Y-388000D02*
Y1475775D01*
X-407000D01*
Y-386798D01*
Y-755294D01*
Y-793716D01*
X-368578D01*
X1942346D01*
X2010999D01*
Y-725063D01*
Y-388000D01*
G01X-53307Y-609436D02*
Y-684436D01*
X446693D01*
Y-609436D01*
X-53307D01*
G01X-41307Y-674436D02*
Y-679436D01*
G01X-42764Y-674436D02*
X-39850D01*
G01X-34940Y-679436D02*
X-37474D01*
Y-674436D01*
X-34940D01*
G01X-35954Y-676853D02*
X-37474D01*
G01X-32374Y-674436D02*
Y-679436D01*
X-29840D01*
G01X-26007Y-679603D02*
X-26134Y-679519D01*
Y-679353D01*
X-26007Y-679269D01*
X-25880Y-679353D01*
Y-679519D01*
X-26007Y-679603D01*
G01Y-677353D02*
X-26134Y-677269D01*
Y-677103D01*
X-26007Y-677019D01*
X-25880Y-677103D01*
Y-677269D01*
X-26007Y-677353D01*
G01X-21224Y-681103D02*
X-21857Y-680269D01*
X-22174Y-679436D01*
Y-676103D01*
X-21857Y-675269D01*
X-21224Y-674436D01*
G01X-15807D02*
X-16314Y-674603D01*
X-16694Y-675019D01*
X-16947Y-675519D01*
X-17137Y-676186D01*
X-17200Y-676936D01*
X-17137Y-677686D01*
X-16947Y-678353D01*
X-16694Y-678853D01*
X-16314Y-679269D01*
X-15807Y-679436D01*
X-15300Y-679269D01*
X-14920Y-678853D01*
X-14667Y-678353D01*
X-14477Y-677686D01*
X-14414Y-676936D01*
X-14477Y-676186D01*
X-14667Y-675519D01*
X-14920Y-675019D01*
X-15300Y-674603D01*
X-15807Y-674436D01*
G01X-12100Y-678436D02*
X-11720Y-679019D01*
X-11214Y-679353D01*
X-10644Y-679436D01*
X-10137Y-679353D01*
X-9630Y-678936D01*
X-9314Y-678436D01*
X-9250Y-677936D01*
X-9377Y-677353D01*
X-9820Y-676936D01*
X-10264Y-676769D01*
X-10834D01*
G01X-10264D02*
X-9884Y-676519D01*
X-9567Y-676103D01*
X-9440Y-675603D01*
X-9567Y-675103D01*
X-9884Y-674686D01*
X-10454Y-674436D01*
X-11024Y-674519D01*
X-11594Y-674853D01*
G01X-5290Y-681103D02*
X-4657Y-680269D01*
X-4340Y-679436D01*
Y-676103D01*
X-4657Y-675269D01*
X-5290Y-674436D01*
G01X-1900Y-678436D02*
X-1520Y-679019D01*
X-1014Y-679353D01*
X-444Y-679436D01*
X63Y-679353D01*
X570Y-678936D01*
X886Y-678436D01*
X950Y-677936D01*
X823Y-677353D01*
X380Y-676936D01*
X-64Y-676769D01*
X-634D01*
G01X-64D02*
X316Y-676519D01*
X633Y-676103D01*
X760Y-675603D01*
X633Y-675103D01*
X316Y-674686D01*
X-254Y-674436D01*
X-824Y-674519D01*
X-1394Y-674853D01*
G01X3390Y-675269D02*
X3770Y-674769D01*
X4213Y-674519D01*
X4720Y-674436D01*
X5353Y-674603D01*
X5796Y-675019D01*
X5923Y-675519D01*
X5860Y-676019D01*
X5606Y-676436D01*
X4340Y-677269D01*
X3770Y-677853D01*
X3390Y-678686D01*
X3263Y-679436D01*
X5923D01*
G01X9566D02*
X9693Y-678353D01*
X9883Y-677436D01*
X10136Y-676603D01*
X10453Y-675686D01*
X10960Y-674436D01*
X8426D01*
G01X13970Y-677769D02*
X15616D01*
G01X18690Y-675269D02*
X19070Y-674769D01*
X19513Y-674519D01*
X20020Y-674436D01*
X20653Y-674603D01*
X21096Y-675019D01*
X21223Y-675519D01*
X21160Y-676019D01*
X20906Y-676436D01*
X19640Y-677269D01*
X19070Y-677853D01*
X18690Y-678686D01*
X18563Y-679436D01*
X21223D01*
G01X23600Y-678436D02*
X23980Y-679019D01*
X24486Y-679353D01*
X25056Y-679436D01*
X25563Y-679353D01*
X26070Y-678936D01*
X26386Y-678436D01*
X26450Y-677936D01*
X26323Y-677353D01*
X25880Y-676936D01*
X25436Y-676769D01*
X24866D01*
G01X25436D02*
X25816Y-676519D01*
X26133Y-676103D01*
X26260Y-675603D01*
X26133Y-675103D01*
X25816Y-674686D01*
X25246Y-674436D01*
X24676Y-674519D01*
X24106Y-674853D01*
G01X30853Y-679436D02*
Y-674436D01*
X28510Y-678019D01*
X31676D01*
G01X33800Y-678686D02*
X34180Y-679103D01*
X34623Y-679353D01*
X35193Y-679436D01*
X35763Y-679269D01*
X36206Y-678936D01*
X36523Y-678353D01*
X36586Y-677686D01*
X36460Y-677019D01*
X36143Y-676603D01*
X35700Y-676269D01*
X35256Y-676186D01*
X34813Y-676269D01*
X34243Y-676603D01*
X34433Y-674436D01*
X36143D01*
G01X44190Y-679436D02*
Y-674436D01*
X46596D01*
G01X45710Y-676853D02*
X44190D01*
G01X48910Y-679436D02*
X50493Y-674436D01*
X52076Y-679436D01*
G01X51506Y-677686D02*
X49480D01*
G01X54263Y-679436D02*
X56923Y-674436D01*
G01X54263D02*
X56923Y-679436D01*
G01X60693Y-679603D02*
X60566Y-679519D01*
Y-679353D01*
X60693Y-679269D01*
X60820Y-679353D01*
Y-679519D01*
X60693Y-679603D01*
G01Y-677353D02*
X60566Y-677269D01*
Y-677103D01*
X60693Y-677019D01*
X60820Y-677103D01*
Y-677269D01*
X60693Y-677353D01*
G01X65476Y-681103D02*
X64843Y-680269D01*
X64526Y-679436D01*
Y-676103D01*
X64843Y-675269D01*
X65476Y-674436D01*
G01X70893D02*
X70386Y-674603D01*
X70006Y-675019D01*
X69753Y-675519D01*
X69563Y-676186D01*
X69500Y-676936D01*
X69563Y-677686D01*
X69753Y-678353D01*
X70006Y-678853D01*
X70386Y-679269D01*
X70893Y-679436D01*
X71400Y-679269D01*
X71780Y-678853D01*
X72033Y-678353D01*
X72223Y-677686D01*
X72286Y-676936D01*
X72223Y-676186D01*
X72033Y-675519D01*
X71780Y-675019D01*
X71400Y-674603D01*
X70893Y-674436D01*
G01X74600Y-678436D02*
X74980Y-679019D01*
X75486Y-679353D01*
X76056Y-679436D01*
X76563Y-679353D01*
X77070Y-678936D01*
X77386Y-678436D01*
X77450Y-677936D01*
X77323Y-677353D01*
X76880Y-676936D01*
X76436Y-676769D01*
X75866D01*
G01X76436D02*
X76816Y-676519D01*
X77133Y-676103D01*
X77260Y-675603D01*
X77133Y-675103D01*
X76816Y-674686D01*
X76246Y-674436D01*
X75676Y-674519D01*
X75106Y-674853D01*
G01X81410Y-681103D02*
X82043Y-680269D01*
X82360Y-679436D01*
Y-676103D01*
X82043Y-675269D01*
X81410Y-674436D01*
G01X84800Y-678436D02*
X85180Y-679019D01*
X85686Y-679353D01*
X86256Y-679436D01*
X86763Y-679353D01*
X87270Y-678936D01*
X87586Y-678436D01*
X87650Y-677936D01*
X87523Y-677353D01*
X87080Y-676936D01*
X86636Y-676769D01*
X86066D01*
G01X86636D02*
X87016Y-676519D01*
X87333Y-676103D01*
X87460Y-675603D01*
X87333Y-675103D01*
X87016Y-674686D01*
X86446Y-674436D01*
X85876Y-674519D01*
X85306Y-674853D01*
G01X90216Y-678853D02*
X90660Y-679269D01*
X91166Y-679436D01*
X91673Y-679269D01*
X92116Y-678769D01*
X92433Y-678019D01*
X92560Y-677269D01*
Y-676353D01*
X92433Y-675603D01*
X92116Y-674936D01*
X91736Y-674603D01*
X91293Y-674436D01*
X90786Y-674603D01*
X90406Y-674936D01*
X90153Y-675436D01*
X90026Y-676103D01*
X90153Y-676686D01*
X90470Y-677269D01*
X90850Y-677603D01*
X91293Y-677686D01*
X91800Y-677519D01*
X92180Y-677103D01*
X92560Y-676353D01*
G01X96266Y-679436D02*
X96393Y-678353D01*
X96583Y-677436D01*
X96836Y-676603D01*
X97153Y-675686D01*
X97660Y-674436D01*
X95126D01*
G01X100670Y-677769D02*
X102316D01*
G01X105200Y-678436D02*
X105580Y-679019D01*
X106086Y-679353D01*
X106656Y-679436D01*
X107163Y-679353D01*
X107670Y-678936D01*
X107986Y-678436D01*
X108050Y-677936D01*
X107923Y-677353D01*
X107480Y-676936D01*
X107036Y-676769D01*
X106466D01*
G01X107036D02*
X107416Y-676519D01*
X107733Y-676103D01*
X107860Y-675603D01*
X107733Y-675103D01*
X107416Y-674686D01*
X106846Y-674436D01*
X106276Y-674519D01*
X105706Y-674853D01*
G01X110490Y-677353D02*
X110933Y-676769D01*
X111313Y-676436D01*
X111820Y-676269D01*
X112263Y-676436D01*
X112580Y-676769D01*
X112833Y-677269D01*
X112896Y-677853D01*
X112833Y-678353D01*
X112580Y-678853D01*
X112200Y-679269D01*
X111756Y-679436D01*
X111250Y-679269D01*
X110806Y-678769D01*
X110553Y-678019D01*
X110490Y-677186D01*
X110616Y-676103D01*
X110806Y-675519D01*
X111123Y-674936D01*
X111566Y-674519D01*
X112010Y-674436D01*
X112453Y-674603D01*
X112770Y-675019D01*
G01X116793Y-679436D02*
Y-674436D01*
X116033Y-675436D01*
G01Y-679436D02*
X117553D01*
G01X122653D02*
Y-674436D01*
X120310Y-678019D01*
X123476D01*
G01X141693Y-609436D02*
Y-684436D01*
G01Y-659436D02*
X244693D01*
Y-634436D01*
G01X141693D02*
X244693D01*
G01X246693Y-609436D02*
Y-684436D01*
G01X244693Y-609436D02*
Y-684436D01*
G01X252200Y-669436D02*
Y-664436D01*
X253466D01*
X253973Y-664686D01*
X254353Y-665019D01*
X254670Y-665519D01*
X254923Y-666103D01*
X254986Y-666936D01*
X254923Y-667769D01*
X254670Y-668353D01*
X254353Y-668853D01*
X253973Y-669186D01*
X253466Y-669436D01*
X252200D01*
G01X257110D02*
X258693Y-664436D01*
X260276Y-669436D01*
G01X259706Y-667686D02*
X257680D01*
G01X263793Y-664436D02*
Y-669436D01*
G01X262336Y-664436D02*
X265250D01*
G01X270160Y-669436D02*
X267626D01*
Y-664436D01*
X270160D01*
G01X269146Y-666853D02*
X267626D01*
G01X273993Y-669603D02*
X273866Y-669519D01*
Y-669353D01*
X273993Y-669269D01*
X274120Y-669353D01*
Y-669519D01*
X273993Y-669603D01*
G01Y-667353D02*
X273866Y-667269D01*
Y-667103D01*
X273993Y-667019D01*
X274120Y-667103D01*
Y-667269D01*
X273993Y-667353D01*
G01X246693Y-659436D02*
X446693D01*
G01X252326Y-644436D02*
Y-639436D01*
X253846D01*
X254353Y-639686D01*
X254733Y-640269D01*
X254860Y-640936D01*
X254733Y-641603D01*
X254416Y-642103D01*
X253846Y-642353D01*
X252326D01*
G01X257553Y-644603D02*
X259833Y-639436D01*
G01X262336Y-644436D02*
Y-639436D01*
X265250Y-644436D01*
Y-639436D01*
G01X268893Y-644603D02*
X268766Y-644519D01*
Y-644353D01*
X268893Y-644269D01*
X269020Y-644353D01*
Y-644519D01*
X268893Y-644603D01*
G01Y-642353D02*
X268766Y-642269D01*
Y-642103D01*
X268893Y-642019D01*
X269020Y-642103D01*
Y-642269D01*
X268893Y-642353D01*
G01X246693Y-634436D02*
X446693D01*
G01X252326Y-619436D02*
Y-614436D01*
X253846D01*
X254353Y-614686D01*
X254733Y-615269D01*
X254860Y-615936D01*
X254733Y-616603D01*
X254416Y-617103D01*
X253846Y-617353D01*
X252326D01*
G01X257426Y-619436D02*
Y-614436D01*
X259010D01*
X259516Y-614686D01*
X259833Y-615019D01*
X259960Y-615686D01*
X259833Y-616353D01*
X259453Y-616769D01*
X259010Y-617019D01*
X257426D01*
G01X259010D02*
X259960Y-619436D01*
G01X263793D02*
X263286Y-619353D01*
X262843Y-619019D01*
X262463Y-618519D01*
X262210Y-617936D01*
X262083Y-617269D01*
Y-616603D01*
X262210Y-615936D01*
X262463Y-615353D01*
X262843Y-614853D01*
X263286Y-614519D01*
X263793Y-614436D01*
X264300Y-614519D01*
X264743Y-614853D01*
X265123Y-615353D01*
X265376Y-615936D01*
X265503Y-616603D01*
Y-617269D01*
X265376Y-617936D01*
X265123Y-618519D01*
X264743Y-619019D01*
X264300Y-619353D01*
X263793Y-619436D01*
G01X267626Y-618436D02*
X267943Y-618936D01*
X268323Y-619269D01*
X268766Y-619436D01*
X269273Y-619269D01*
X269653Y-618936D01*
X270033Y-618436D01*
X270160Y-617769D01*
Y-614436D01*
G01X275260Y-619436D02*
X272726D01*
Y-614436D01*
X275260D01*
G01X274246Y-616853D02*
X272726D01*
G01X280486Y-614853D02*
X280106Y-614603D01*
X279663Y-614436D01*
X279156D01*
X278586Y-614686D01*
X278143Y-615103D01*
X277826Y-615603D01*
X277573Y-616436D01*
X277510Y-617186D01*
X277636Y-617936D01*
X277826Y-618436D01*
X278206Y-618936D01*
X278650Y-619269D01*
X279093Y-619436D01*
X279536D01*
X279980Y-619269D01*
X280360Y-619019D01*
X280676Y-618686D01*
G01X284193Y-614436D02*
Y-619436D01*
G01X282736Y-614436D02*
X285650D01*
G01X289293Y-619603D02*
X289166Y-619519D01*
Y-619353D01*
X289293Y-619269D01*
X289420Y-619353D01*
Y-619519D01*
X289293Y-619603D01*
G01Y-617353D02*
X289166Y-617269D01*
Y-617103D01*
X289293Y-617019D01*
X289420Y-617103D01*
Y-617269D01*
X289293Y-617353D01*
G01X361693Y-659436D02*
Y-684436D01*
G01X364326Y-661936D02*
Y-666936D01*
X366860D01*
G01X369933Y-661936D02*
X371453D01*
G01X370693D02*
Y-666936D01*
G01X369933D02*
X371453D01*
G01X376300Y-664269D02*
X376553Y-664019D01*
X376743Y-663603D01*
X376870Y-663019D01*
X376743Y-662519D01*
X376490Y-662186D01*
X376046Y-661936D01*
X374336D01*
Y-666936D01*
X376426D01*
X376870Y-666603D01*
X377123Y-666103D01*
X377250Y-665519D01*
X377123Y-664936D01*
X376743Y-664436D01*
X376300Y-664269D01*
X374336D01*
G01X380893Y-667103D02*
X380766Y-667019D01*
Y-666853D01*
X380893Y-666769D01*
X381020Y-666853D01*
Y-667019D01*
X380893Y-667103D01*
G01Y-664853D02*
X380766Y-664769D01*
Y-664603D01*
X380893Y-664519D01*
X381020Y-664603D01*
Y-664769D01*
X380893Y-664853D01*
G01X404693Y-659436D02*
Y-684436D01*
G01Y-634436D02*
Y-659436D01*
G01X412706Y-687603D02*
X412813Y-687478D01*
X412893Y-687269D01*
X412946Y-686978D01*
X412893Y-686728D01*
X412786Y-686561D01*
X412600Y-686436D01*
X411880D01*
Y-688936D01*
X412760D01*
X412946Y-688769D01*
X413053Y-688519D01*
X413106Y-688228D01*
X413053Y-687936D01*
X412893Y-687686D01*
X412706Y-687603D01*
X411880D01*
G01X415173Y-688936D02*
Y-687269D01*
G01Y-687561D02*
X415066Y-687394D01*
X414906Y-687311D01*
X414720Y-687269D01*
X414533Y-687353D01*
X414373Y-687519D01*
X414266Y-687769D01*
X414213Y-688103D01*
X414266Y-688436D01*
X414373Y-688686D01*
X414533Y-688853D01*
X414720Y-688936D01*
X414906Y-688894D01*
X415066Y-688769D01*
X415173Y-688603D01*
G01X416493Y-688644D02*
X416626Y-688811D01*
X416813Y-688936D01*
X416973D01*
X417133Y-688853D01*
X417240Y-688728D01*
X417293Y-688561D01*
X417266Y-688311D01*
X417160Y-688186D01*
X416680Y-687936D01*
X416573Y-687644D01*
X416626Y-687436D01*
X416733Y-687311D01*
X416893Y-687269D01*
X417053Y-687311D01*
X417213Y-687436D01*
G01X418693Y-687811D02*
X419546D01*
X419466Y-687519D01*
X419333Y-687353D01*
X419146Y-687269D01*
X418960Y-687311D01*
X418800Y-687436D01*
X418693Y-687728D01*
X418640Y-687978D01*
Y-688228D01*
X418693Y-688478D01*
X418826Y-688728D01*
X418986Y-688894D01*
X419173Y-688936D01*
X419360Y-688853D01*
X419546Y-688603D01*
G01X420813Y-688936D02*
Y-686436D01*
G01Y-687686D02*
X420946Y-687436D01*
X421106Y-687311D01*
X421266Y-687269D01*
X421506Y-687353D01*
X421666Y-687519D01*
X421773Y-687811D01*
Y-688144D01*
X421720Y-688478D01*
X421613Y-688728D01*
X421426Y-688894D01*
X421266Y-688936D01*
X421106Y-688894D01*
X420946Y-688769D01*
X420813Y-688561D01*
G01X423493Y-688936D02*
X423333Y-688894D01*
X423173Y-688728D01*
X423066Y-688436D01*
X423013Y-688103D01*
X423066Y-687769D01*
X423173Y-687478D01*
X423333Y-687311D01*
X423493Y-687269D01*
X423653Y-687311D01*
X423813Y-687478D01*
X423920Y-687769D01*
X423946Y-688103D01*
X423920Y-688436D01*
X423813Y-688728D01*
X423653Y-688894D01*
X423493Y-688936D01*
G01X426173D02*
Y-687269D01*
G01Y-687561D02*
X426066Y-687394D01*
X425906Y-687311D01*
X425720Y-687269D01*
X425533Y-687353D01*
X425373Y-687519D01*
X425266Y-687769D01*
X425213Y-688103D01*
X425266Y-688436D01*
X425373Y-688686D01*
X425533Y-688853D01*
X425720Y-688936D01*
X425906Y-688894D01*
X426066Y-688769D01*
X426173Y-688603D01*
G01X427520Y-688936D02*
Y-687269D01*
G01Y-687603D02*
X427653Y-687436D01*
X427786Y-687311D01*
X427973Y-687269D01*
X428106Y-687311D01*
X428266Y-687436D01*
G01X430573Y-686436D02*
Y-688936D01*
G01Y-688561D02*
X430466Y-688769D01*
X430306Y-688894D01*
X430120Y-688936D01*
X429906Y-688853D01*
X429746Y-688644D01*
X429640Y-688394D01*
X429613Y-688103D01*
X429640Y-687811D01*
X429746Y-687561D01*
X429906Y-687353D01*
X430120Y-687269D01*
X430306Y-687311D01*
X430440Y-687394D01*
X430573Y-687561D01*
G01X433960Y-688936D02*
Y-686436D01*
X434626D01*
X434840Y-686561D01*
X434973Y-686728D01*
X435026Y-687061D01*
X434973Y-687394D01*
X434813Y-687603D01*
X434626Y-687728D01*
X433960D01*
G01X434626D02*
X435026Y-688936D01*
G01X436293Y-687811D02*
X437146D01*
X437066Y-687519D01*
X436933Y-687353D01*
X436746Y-687269D01*
X436560Y-687311D01*
X436400Y-687436D01*
X436293Y-687728D01*
X436240Y-687978D01*
Y-688228D01*
X436293Y-688478D01*
X436426Y-688728D01*
X436586Y-688894D01*
X436773Y-688936D01*
X436960Y-688853D01*
X437146Y-688603D01*
G01X438413Y-687269D02*
X438893Y-688936D01*
X439373Y-687269D01*
G01X441093Y-689019D02*
X441040Y-688978D01*
Y-688894D01*
X441093Y-688853D01*
X441146Y-688894D01*
Y-688978D01*
X441093Y-689019D01*
G01X443613Y-688936D02*
Y-686436D01*
X442626Y-688228D01*
X443960D01*
G01X444826Y-688936D02*
X445493Y-686436D01*
X446160Y-688936D01*
G01X445920Y-688061D02*
X445066D01*
G01X408593Y-661936D02*
Y-666936D01*
G01X407136Y-661936D02*
X410050D01*
G01X413693Y-666936D02*
X413313Y-666853D01*
X412933Y-666519D01*
X412680Y-665936D01*
X412553Y-665269D01*
X412680Y-664603D01*
X412933Y-664019D01*
X413313Y-663686D01*
X413693Y-663603D01*
X414073Y-663686D01*
X414453Y-664019D01*
X414706Y-664603D01*
X414770Y-665269D01*
X414706Y-665936D01*
X414453Y-666519D01*
X414073Y-666853D01*
X413693Y-666936D01*
G01X418793D02*
X418413Y-666853D01*
X418033Y-666519D01*
X417780Y-665936D01*
X417653Y-665269D01*
X417780Y-664603D01*
X418033Y-664019D01*
X418413Y-663686D01*
X418793Y-663603D01*
X419173Y-663686D01*
X419553Y-664019D01*
X419806Y-664603D01*
X419870Y-665269D01*
X419806Y-665936D01*
X419553Y-666519D01*
X419173Y-666853D01*
X418793Y-666936D01*
G01X423893D02*
Y-661936D01*
G01X428993Y-667103D02*
X428866Y-667019D01*
Y-666853D01*
X428993Y-666769D01*
X429120Y-666853D01*
Y-667019D01*
X428993Y-667103D01*
G01Y-664853D02*
X428866Y-664769D01*
Y-664603D01*
X428993Y-664519D01*
X429120Y-664603D01*
Y-664769D01*
X428993Y-664853D01*
G01X407326Y-641936D02*
Y-636936D01*
X408910D01*
X409416Y-637186D01*
X409733Y-637519D01*
X409860Y-638186D01*
X409733Y-638853D01*
X409353Y-639269D01*
X408910Y-639519D01*
X407326D01*
G01X408910D02*
X409860Y-641936D01*
G01X414960D02*
X412426D01*
Y-636936D01*
X414960D01*
G01X413946Y-639353D02*
X412426D01*
G01X417210Y-636936D02*
X418793Y-641936D01*
X420376Y-636936D01*
G01X423893Y-642103D02*
X423766Y-642019D01*
Y-641853D01*
X423893Y-641769D01*
X424020Y-641853D01*
Y-642019D01*
X423893Y-642103D01*
G01Y-639853D02*
X423766Y-639769D01*
Y-639603D01*
X423893Y-639519D01*
X424020Y-639603D01*
Y-639769D01*
X423893Y-639853D01*
G01X2010999Y-388000D02*
Y1475775D01*
X-407000D01*
Y-386798D01*
Y-755294D01*
Y-793716D01*
X-368578D01*
X1942346D01*
X2010999D01*
Y-725063D01*
Y-388000D01*
G01X-42602Y-671096D02*
X-41975Y-671621D01*
X-41270Y-671936D01*
X-40644D01*
X-40017Y-671621D01*
X-39547Y-671096D01*
X-39312Y-670361D01*
X-39469Y-669626D01*
X-39860Y-668996D01*
X-40565Y-668576D01*
X-41505Y-668366D01*
X-42054Y-667946D01*
X-42289Y-667211D01*
X-42132Y-666476D01*
X-41740Y-665951D01*
X-41192Y-665636D01*
X-40644D01*
X-40095Y-665846D01*
X-39625Y-666371D01*
G01X-36302Y-671936D02*
Y-665636D01*
G01X-33012D02*
Y-671936D01*
G01Y-668786D02*
X-36302D01*
G01X-29297Y-665636D02*
X-27417D01*
G01X-28357D02*
Y-671936D01*
G01X-29297D02*
X-27417D01*
G01X-20490D02*
X-23624D01*
Y-665636D01*
X-20490D01*
G01X-21744Y-668681D02*
X-23624D01*
G01X-17559Y-671936D02*
Y-665636D01*
X-13955Y-671936D01*
Y-665636D01*
G01X-9614Y-673091D02*
X-9300Y-671726D01*
G01X-3157Y-665636D02*
Y-671936D01*
G01X-4959Y-665636D02*
X-1355D01*
G01X1185Y-671936D02*
X3143Y-665636D01*
X5101Y-671936D01*
G01X4396Y-669731D02*
X1890D01*
G01X8503Y-665636D02*
X10383D01*
G01X9443D02*
Y-671936D01*
G01X8503D02*
X10383D01*
G01X13393Y-665636D02*
X14490Y-671936D01*
X15743Y-665636D01*
X16996Y-671936D01*
X18093Y-665636D01*
G01X20085Y-671936D02*
X22043Y-665636D01*
X24001Y-671936D01*
G01X23296Y-669731D02*
X20790D01*
G01X26541Y-671936D02*
Y-665636D01*
X30145Y-671936D01*
Y-665636D01*
G01X39376Y-671936D02*
Y-665636D01*
X41335D01*
X41961Y-665951D01*
X42353Y-666371D01*
X42510Y-667211D01*
X42353Y-668051D01*
X41883Y-668576D01*
X41335Y-668891D01*
X39376D01*
G01X41335D02*
X42510Y-671936D01*
G01X47243Y-672146D02*
X47086Y-672041D01*
Y-671831D01*
X47243Y-671726D01*
X47400Y-671831D01*
Y-672041D01*
X47243Y-672146D01*
G01X53543Y-671936D02*
X52916Y-671831D01*
X52368Y-671411D01*
X51898Y-670781D01*
X51585Y-670046D01*
X51428Y-669206D01*
Y-668366D01*
X51585Y-667526D01*
X51898Y-666791D01*
X52368Y-666161D01*
X52916Y-665741D01*
X53543Y-665636D01*
X54170Y-665741D01*
X54718Y-666161D01*
X55188Y-666791D01*
X55501Y-667526D01*
X55658Y-668366D01*
Y-669206D01*
X55501Y-670046D01*
X55188Y-670781D01*
X54718Y-671411D01*
X54170Y-671831D01*
X53543Y-671936D01*
G01X59843Y-672146D02*
X59686Y-672041D01*
Y-671831D01*
X59843Y-671726D01*
X60000Y-671831D01*
Y-672041D01*
X59843Y-672146D01*
G01X67866Y-666161D02*
X67396Y-665846D01*
X66848Y-665636D01*
X66221D01*
X65516Y-665951D01*
X64968Y-666476D01*
X64576Y-667106D01*
X64263Y-668156D01*
X64185Y-669101D01*
X64341Y-670046D01*
X64576Y-670676D01*
X65046Y-671306D01*
X65595Y-671726D01*
X66143Y-671936D01*
X66691D01*
X67240Y-671726D01*
X67710Y-671411D01*
X68101Y-670991D01*
G01X72443Y-672146D02*
X72286Y-672041D01*
Y-671831D01*
X72443Y-671726D01*
X72600Y-671831D01*
Y-672041D01*
X72443Y-672146D01*
G01X-42680Y-661936D02*
Y-655636D01*
G01X-39704D02*
X-42680Y-659521D01*
G01X-39234Y-661936D02*
X-41349Y-657736D01*
G01X-36380Y-655636D02*
Y-660151D01*
X-36067Y-661096D01*
X-35440Y-661726D01*
X-34657Y-661936D01*
X-33874Y-661726D01*
X-33247Y-661096D01*
X-32934Y-660151D01*
Y-655636D01*
G01X-26790Y-661936D02*
X-29924D01*
Y-655636D01*
X-26790D01*
G01X-28044Y-658681D02*
X-29924D01*
G01X-22997Y-655636D02*
X-21117D01*
G01X-22057D02*
Y-661936D01*
G01X-22997D02*
X-21117D01*
G01X-11102Y-661096D02*
X-10475Y-661621D01*
X-9770Y-661936D01*
X-9144D01*
X-8517Y-661621D01*
X-8047Y-661096D01*
X-7812Y-660361D01*
X-7969Y-659626D01*
X-8360Y-658996D01*
X-9065Y-658576D01*
X-10005Y-658366D01*
X-10554Y-657946D01*
X-10789Y-657211D01*
X-10632Y-656476D01*
X-10240Y-655951D01*
X-9692Y-655636D01*
X-9144D01*
X-8595Y-655846D01*
X-8125Y-656371D01*
G01X-4802Y-661936D02*
Y-655636D01*
G01X-1512D02*
Y-661936D01*
G01Y-658786D02*
X-4802D01*
G01X1185Y-661936D02*
X3143Y-655636D01*
X5101Y-661936D01*
G01X4396Y-659731D02*
X1890D01*
G01X7641Y-661936D02*
Y-655636D01*
X11245Y-661936D01*
Y-655636D01*
G01X20398Y-661936D02*
Y-655636D01*
G01X23688D02*
Y-661936D01*
G01Y-658786D02*
X20398D01*
G01X26698Y-661096D02*
X27325Y-661621D01*
X28030Y-661936D01*
X28656D01*
X29283Y-661621D01*
X29753Y-661096D01*
X29988Y-660361D01*
X29831Y-659626D01*
X29440Y-658996D01*
X28735Y-658576D01*
X27795Y-658366D01*
X27246Y-657946D01*
X27011Y-657211D01*
X27168Y-656476D01*
X27560Y-655951D01*
X28108Y-655636D01*
X28656D01*
X29205Y-655846D01*
X29675Y-656371D01*
G01X33703Y-655636D02*
X35583D01*
G01X34643D02*
Y-661936D01*
G01X33703D02*
X35583D01*
G01X38985D02*
X40943Y-655636D01*
X42901Y-661936D01*
G01X42196Y-659731D02*
X39690D01*
G01X45441Y-661936D02*
Y-655636D01*
X49045Y-661936D01*
Y-655636D01*
G01X54013Y-658786D02*
X55580D01*
Y-660676D01*
X55110Y-661306D01*
X54561Y-661726D01*
X53778Y-661936D01*
X52995Y-661726D01*
X52446Y-661306D01*
X51976Y-660676D01*
X51663Y-659941D01*
X51506Y-659101D01*
Y-658366D01*
X51663Y-657736D01*
X51976Y-657001D01*
X52446Y-656371D01*
X52916Y-655951D01*
X53543Y-655636D01*
X54091D01*
X54718Y-655846D01*
X55188Y-656266D01*
G01X59686Y-663091D02*
X60000Y-661726D01*
G01X66143Y-655636D02*
Y-661936D01*
G01X64341Y-655636D02*
X67945D01*
G01X70485Y-661936D02*
X72443Y-655636D01*
X74401Y-661936D01*
G01X73696Y-659731D02*
X71190D01*
G01X78743Y-661936D02*
X78116Y-661831D01*
X77568Y-661411D01*
X77098Y-660781D01*
X76785Y-660046D01*
X76628Y-659206D01*
Y-658366D01*
X76785Y-657526D01*
X77098Y-656791D01*
X77568Y-656161D01*
X78116Y-655741D01*
X78743Y-655636D01*
X79370Y-655741D01*
X79918Y-656161D01*
X80388Y-656791D01*
X80701Y-657526D01*
X80858Y-658366D01*
Y-659206D01*
X80701Y-660046D01*
X80388Y-660781D01*
X79918Y-661411D01*
X79370Y-661831D01*
X78743Y-661936D01*
G01X91343D02*
Y-659101D01*
X89776Y-655636D01*
G01X92910D02*
X91343Y-659101D01*
G01X95920Y-655636D02*
Y-660151D01*
X96233Y-661096D01*
X96860Y-661726D01*
X97643Y-661936D01*
X98426Y-661726D01*
X99053Y-661096D01*
X99366Y-660151D01*
Y-655636D01*
G01X101985Y-661936D02*
X103943Y-655636D01*
X105901Y-661936D01*
G01X105196Y-659731D02*
X102690D01*
G01X108441Y-661936D02*
Y-655636D01*
X112045Y-661936D01*
Y-655636D01*
G01X-42759Y-651936D02*
Y-645636D01*
X-39155Y-651936D01*
Y-645636D01*
G01X-34657Y-651936D02*
X-35284Y-651831D01*
X-35832Y-651411D01*
X-36302Y-650781D01*
X-36615Y-650046D01*
X-36772Y-649206D01*
Y-648366D01*
X-36615Y-647526D01*
X-36302Y-646791D01*
X-35832Y-646161D01*
X-35284Y-645741D01*
X-34657Y-645636D01*
X-34030Y-645741D01*
X-33482Y-646161D01*
X-33012Y-646791D01*
X-32699Y-647526D01*
X-32542Y-648366D01*
Y-649206D01*
X-32699Y-650046D01*
X-33012Y-650781D01*
X-33482Y-651411D01*
X-34030Y-651831D01*
X-34657Y-651936D01*
G01X-28357Y-652146D02*
X-28514Y-652041D01*
Y-651831D01*
X-28357Y-651726D01*
X-28200Y-651831D01*
Y-652041D01*
X-28357Y-652146D01*
G01X-22057Y-651936D02*
Y-645636D01*
X-22997Y-646896D01*
G01Y-651936D02*
X-21117D01*
G01X-15757D02*
X-15209Y-651831D01*
X-14582Y-651516D01*
X-14190Y-650991D01*
X-14034Y-650256D01*
X-14190Y-649521D01*
X-14660Y-648891D01*
X-15365Y-648576D01*
X-16149D01*
X-16619Y-648366D01*
X-17010Y-647841D01*
X-17167Y-647106D01*
X-16932Y-646371D01*
X-16384Y-645846D01*
X-15757Y-645636D01*
X-15130Y-645846D01*
X-14582Y-646371D01*
X-14347Y-647106D01*
X-14504Y-647841D01*
X-14895Y-648366D01*
X-15365Y-648576D01*
X-16149D01*
X-16854Y-648891D01*
X-17324Y-649521D01*
X-17480Y-650256D01*
X-17324Y-650991D01*
X-16932Y-651516D01*
X-16305Y-651831D01*
X-15757Y-651936D01*
G01X-9457D02*
X-8909Y-651831D01*
X-8282Y-651516D01*
X-7890Y-650991D01*
X-7734Y-650256D01*
X-7890Y-649521D01*
X-8360Y-648891D01*
X-9065Y-648576D01*
X-9849D01*
X-10319Y-648366D01*
X-10710Y-647841D01*
X-10867Y-647106D01*
X-10632Y-646371D01*
X-10084Y-645846D01*
X-9457Y-645636D01*
X-8830Y-645846D01*
X-8282Y-646371D01*
X-8047Y-647106D01*
X-8204Y-647841D01*
X-8595Y-648366D01*
X-9065Y-648576D01*
X-9849D01*
X-10554Y-648891D01*
X-11024Y-649521D01*
X-11180Y-650256D01*
X-11024Y-650991D01*
X-10632Y-651516D01*
X-10005Y-651831D01*
X-9457Y-651936D01*
G01X-3314Y-653091D02*
X-3000Y-651726D01*
G01X793Y-645636D02*
X1890Y-651936D01*
X3143Y-645636D01*
X4396Y-651936D01*
X5493Y-645636D01*
G01X11010Y-651936D02*
X7876D01*
Y-645636D01*
X11010D01*
G01X9756Y-648681D02*
X7876D01*
G01X13941Y-651936D02*
Y-645636D01*
X17545Y-651936D01*
Y-645636D01*
G01X26698Y-651936D02*
Y-645636D01*
G01X29988D02*
Y-651936D01*
G01Y-648786D02*
X26698D01*
G01X32293Y-645636D02*
X33390Y-651936D01*
X34643Y-645636D01*
X35896Y-651936D01*
X36993Y-645636D01*
G01X38985Y-651936D02*
X40943Y-645636D01*
X42901Y-651936D01*
G01X42196Y-649731D02*
X39690D01*
G01X52055Y-646686D02*
X52525Y-646056D01*
X53073Y-645741D01*
X53700Y-645636D01*
X54483Y-645846D01*
X55031Y-646371D01*
X55188Y-647001D01*
X55110Y-647631D01*
X54796Y-648156D01*
X53230Y-649206D01*
X52525Y-649941D01*
X52055Y-650991D01*
X51898Y-651936D01*
X55188D01*
G01X58041D02*
Y-645636D01*
X61645Y-651936D01*
Y-645636D01*
G01X64420Y-651936D02*
Y-645636D01*
X65986D01*
X66613Y-645951D01*
X67083Y-646371D01*
X67475Y-647001D01*
X67788Y-647736D01*
X67866Y-648786D01*
X67788Y-649836D01*
X67475Y-650571D01*
X67083Y-651201D01*
X66613Y-651621D01*
X65986Y-651936D01*
X64420D01*
G01X77176D02*
Y-645636D01*
X79135D01*
X79761Y-645951D01*
X80153Y-646371D01*
X80310Y-647211D01*
X80153Y-648051D01*
X79683Y-648576D01*
X79135Y-648891D01*
X77176D01*
G01X79135D02*
X80310Y-651936D01*
G01X83320D02*
Y-645636D01*
X84886D01*
X85513Y-645951D01*
X85983Y-646371D01*
X86375Y-647001D01*
X86688Y-647736D01*
X86766Y-648786D01*
X86688Y-649836D01*
X86375Y-650571D01*
X85983Y-651201D01*
X85513Y-651621D01*
X84886Y-651936D01*
X83320D01*
G01X91343Y-652146D02*
X91186Y-652041D01*
Y-651831D01*
X91343Y-651726D01*
X91500Y-651831D01*
Y-652041D01*
X91343Y-652146D01*
G01X-18657Y-639236D02*
X-21177Y-638819D01*
X-23382Y-637153D01*
X-25272Y-634653D01*
X-26532Y-631736D01*
X-27162Y-628403D01*
Y-625069D01*
X-26532Y-621736D01*
X-25272Y-618819D01*
X-23382Y-616320D01*
X-21177Y-614653D01*
X-18657Y-614236D01*
X-16137Y-614653D01*
X-13932Y-616320D01*
X-12042Y-618819D01*
X-10782Y-621736D01*
X-10152Y-625069D01*
Y-628403D01*
X-10782Y-631736D01*
X-12042Y-634653D01*
X-13932Y-637153D01*
X-16137Y-638819D01*
X-18657Y-639236D01*
G01X-16137Y-632569D02*
X-12357Y-639236D01*
G01X1188Y-622570D02*
Y-634236D01*
X2448Y-637153D01*
X4338Y-638819D01*
X6543Y-639236D01*
X8748Y-638819D01*
X10638Y-637153D01*
X11898Y-634236D01*
G01Y-639236D02*
Y-622570D01*
G01X37413Y-639236D02*
Y-622570D01*
G01Y-625486D02*
X36153Y-623820D01*
X34263Y-622986D01*
X32058Y-622570D01*
X29853Y-623403D01*
X27963Y-625069D01*
X26703Y-627570D01*
X26073Y-630903D01*
X26703Y-634236D01*
X27963Y-636737D01*
X29853Y-638403D01*
X32058Y-639236D01*
X34263Y-638819D01*
X36153Y-637570D01*
X37413Y-635903D01*
G01X51588Y-639236D02*
Y-622570D01*
G01Y-626736D02*
X52848Y-624653D01*
X54738Y-622986D01*
X57258Y-622570D01*
X59463Y-622986D01*
X61353Y-624653D01*
X62298Y-627570D01*
Y-639236D01*
G01X82143Y-614236D02*
Y-639236D01*
G01X77733Y-622570D02*
X86553D01*
G01X113013Y-639236D02*
Y-622570D01*
G01Y-625486D02*
X111753Y-623820D01*
X109863Y-622986D01*
X107658Y-622570D01*
X105453Y-623403D01*
X103563Y-625069D01*
X102303Y-627570D01*
X101673Y-630903D01*
X102303Y-634236D01*
X103563Y-636737D01*
X105453Y-638403D01*
X107658Y-639236D01*
X109863Y-638819D01*
X111753Y-637570D01*
X113013Y-635903D01*
G01X152693Y-618936D02*
Y-626936D01*
X156693D01*
G01X164493D02*
Y-621603D01*
G01Y-622536D02*
X164093Y-622003D01*
X163493Y-621736D01*
X162793Y-621603D01*
X162093Y-621869D01*
X161493Y-622403D01*
X161093Y-623203D01*
X160893Y-624269D01*
X161093Y-625336D01*
X161493Y-626136D01*
X162093Y-626669D01*
X162793Y-626936D01*
X163493Y-626803D01*
X164093Y-626403D01*
X164493Y-625870D01*
G01X168593Y-629336D02*
X169193Y-629603D01*
X169993Y-629336D01*
X170493Y-628803D01*
X170893Y-628136D01*
X171493Y-626003D01*
X172793Y-621603D01*
G01X169593D02*
X171493Y-626003D01*
G01X177193Y-623336D02*
X180393D01*
X180093Y-622403D01*
X179593Y-621869D01*
X178893Y-621603D01*
X178193Y-621736D01*
X177593Y-622136D01*
X177193Y-623069D01*
X176993Y-623870D01*
Y-624669D01*
X177193Y-625469D01*
X177693Y-626269D01*
X178293Y-626803D01*
X178993Y-626936D01*
X179693Y-626669D01*
X180393Y-625870D01*
G01X185293Y-626936D02*
Y-621603D01*
G01Y-622669D02*
X185793Y-622136D01*
X186293Y-621736D01*
X186993Y-621603D01*
X187493Y-621736D01*
X188093Y-622136D01*
G01X173993Y-676936D02*
Y-668936D01*
G01X177793D02*
X173993Y-673870D01*
G01X178393Y-676936D02*
X175693Y-671603D01*
G01X185993Y-676936D02*
Y-671603D01*
G01Y-672536D02*
X185593Y-672003D01*
X184993Y-671736D01*
X184293Y-671603D01*
X183593Y-671869D01*
X182993Y-672403D01*
X182593Y-673203D01*
X182393Y-674269D01*
X182593Y-675336D01*
X182993Y-676136D01*
X183593Y-676669D01*
X184293Y-676936D01*
X184993Y-676803D01*
X185593Y-676403D01*
X185993Y-675870D01*
G01X192193Y-671603D02*
Y-676936D01*
G01Y-669469D02*
X191993Y-669336D01*
Y-669069D01*
X192193Y-668936D01*
X192393Y-669069D01*
Y-669336D01*
X192193Y-669469D01*
G01X184993Y-643936D02*
X187393D01*
G01X186193D02*
Y-651936D01*
G01X184993D02*
X187393D01*
G01X191893D02*
Y-643936D01*
X196493Y-651936D01*
Y-643936D01*
G01X200293Y-645269D02*
X200893Y-644469D01*
X201593Y-644069D01*
X202393Y-643936D01*
X203393Y-644203D01*
X204093Y-644869D01*
X204293Y-645669D01*
X204193Y-646470D01*
X203793Y-647136D01*
X201793Y-648469D01*
X200893Y-649403D01*
X200293Y-650736D01*
X200093Y-651936D01*
X204293D01*
G01X203993Y-625736D02*
X204593Y-626403D01*
X205293Y-626803D01*
X206193Y-626936D01*
X207093Y-626669D01*
X207793Y-626136D01*
X208293Y-625203D01*
X208393Y-624136D01*
X208193Y-623069D01*
X207693Y-622403D01*
X206993Y-621869D01*
X206293Y-621736D01*
X205593Y-621869D01*
X204693Y-622403D01*
X204993Y-618936D01*
X207693D01*
G01X279293Y-670269D02*
X279893Y-669469D01*
X280593Y-669069D01*
X281393Y-668936D01*
X282393Y-669203D01*
X283093Y-669869D01*
X283293Y-670669D01*
X283193Y-671470D01*
X282793Y-672136D01*
X280793Y-673469D01*
X279893Y-674403D01*
X279293Y-675736D01*
X279093Y-676936D01*
X283293D01*
G01X289193Y-668936D02*
X288393Y-669203D01*
X287793Y-669869D01*
X287393Y-670669D01*
X287093Y-671736D01*
X286993Y-672936D01*
X287093Y-674136D01*
X287393Y-675203D01*
X287793Y-676003D01*
X288393Y-676669D01*
X289193Y-676936D01*
X289993Y-676669D01*
X290593Y-676003D01*
X290993Y-675203D01*
X291293Y-674136D01*
X291393Y-672936D01*
X291293Y-671736D01*
X290993Y-670669D01*
X290593Y-669869D01*
X289993Y-669203D01*
X289193Y-668936D01*
G01X295293Y-670269D02*
X295893Y-669469D01*
X296593Y-669069D01*
X297393Y-668936D01*
X298393Y-669203D01*
X299093Y-669869D01*
X299293Y-670669D01*
X299193Y-671470D01*
X298793Y-672136D01*
X296793Y-673469D01*
X295893Y-674403D01*
X295293Y-675736D01*
X295093Y-676936D01*
X299293D01*
G01X303293Y-670269D02*
X303893Y-669469D01*
X304593Y-669069D01*
X305393Y-668936D01*
X306393Y-669203D01*
X307093Y-669869D01*
X307293Y-670669D01*
X307193Y-671470D01*
X306793Y-672136D01*
X304793Y-673469D01*
X303893Y-674403D01*
X303293Y-675736D01*
X303093Y-676936D01*
X307293D01*
G01X311393Y-677203D02*
X314993Y-668936D01*
G01X321193Y-676936D02*
Y-668936D01*
X319993Y-670536D01*
G01Y-676936D02*
X322393D01*
G01X327293Y-670269D02*
X327893Y-669469D01*
X328593Y-669069D01*
X329393Y-668936D01*
X330393Y-669203D01*
X331093Y-669869D01*
X331293Y-670669D01*
X331193Y-671470D01*
X330793Y-672136D01*
X328793Y-673469D01*
X327893Y-674403D01*
X327293Y-675736D01*
X327093Y-676936D01*
X331293D01*
G01X335393Y-677203D02*
X338993Y-668936D01*
G01X345193D02*
X344393Y-669203D01*
X343793Y-669869D01*
X343393Y-670669D01*
X343093Y-671736D01*
X342993Y-672936D01*
X343093Y-674136D01*
X343393Y-675203D01*
X343793Y-676003D01*
X344393Y-676669D01*
X345193Y-676936D01*
X345993Y-676669D01*
X346593Y-676003D01*
X346993Y-675203D01*
X347293Y-674136D01*
X347393Y-672936D01*
X347293Y-671736D01*
X346993Y-670669D01*
X346593Y-669869D01*
X345993Y-669203D01*
X345193Y-668936D01*
G01X351493Y-676003D02*
X352193Y-676669D01*
X352993Y-676936D01*
X353793Y-676669D01*
X354493Y-675870D01*
X354993Y-674669D01*
X355193Y-673469D01*
Y-672003D01*
X354993Y-670803D01*
X354493Y-669736D01*
X353893Y-669203D01*
X353193Y-668936D01*
X352393Y-669203D01*
X351793Y-669736D01*
X351393Y-670536D01*
X351193Y-671603D01*
X351393Y-672536D01*
X351893Y-673469D01*
X352493Y-674003D01*
X353193Y-674136D01*
X353993Y-673870D01*
X354593Y-673203D01*
X355193Y-672003D01*
G01X278993Y-651936D02*
Y-643936D01*
X280993D01*
X281793Y-644336D01*
X282393Y-644869D01*
X282893Y-645669D01*
X283293Y-646603D01*
X283393Y-647936D01*
X283293Y-649269D01*
X282893Y-650203D01*
X282393Y-651003D01*
X281793Y-651536D01*
X280993Y-651936D01*
X278993D01*
G01X286693D02*
X289193Y-643936D01*
X291693Y-651936D01*
G01X290793Y-649136D02*
X287593D01*
G01X297193Y-643936D02*
X296393Y-644203D01*
X295793Y-644869D01*
X295393Y-645669D01*
X295093Y-646736D01*
X294993Y-647936D01*
X295093Y-649136D01*
X295393Y-650203D01*
X295793Y-651003D01*
X296393Y-651669D01*
X297193Y-651936D01*
X297993Y-651669D01*
X298593Y-651003D01*
X298993Y-650203D01*
X299293Y-649136D01*
X299393Y-647936D01*
X299293Y-646736D01*
X298993Y-645669D01*
X298593Y-644869D01*
X297993Y-644203D01*
X297193Y-643936D01*
G01X303293Y-651936D02*
Y-643936D01*
X307093D01*
G01X305693Y-647803D02*
X303293D01*
G01X313193Y-643936D02*
X312393Y-644203D01*
X311793Y-644869D01*
X311393Y-645669D01*
X311093Y-646736D01*
X310993Y-647936D01*
X311093Y-649136D01*
X311393Y-650203D01*
X311793Y-651003D01*
X312393Y-651669D01*
X313193Y-651936D01*
X313993Y-651669D01*
X314593Y-651003D01*
X314993Y-650203D01*
X315293Y-649136D01*
X315393Y-647936D01*
X315293Y-646736D01*
X314993Y-645669D01*
X314593Y-644869D01*
X313993Y-644203D01*
X313193Y-643936D01*
G01X321193D02*
Y-651936D01*
G01X318893Y-643936D02*
X323493D01*
G01X326593Y-651936D02*
Y-643936D01*
X329193Y-650603D01*
X331793Y-643936D01*
Y-651936D01*
G01X334993D02*
Y-643936D01*
X336993D01*
X337793Y-644336D01*
X338393Y-644869D01*
X338893Y-645669D01*
X339293Y-646603D01*
X339393Y-647936D01*
X339293Y-649269D01*
X338893Y-650203D01*
X338393Y-651003D01*
X337793Y-651536D01*
X336993Y-651936D01*
X334993D01*
G01X347393Y-644603D02*
X346793Y-644203D01*
X346093Y-643936D01*
X345293D01*
X344393Y-644336D01*
X343693Y-645003D01*
X343193Y-645803D01*
X342793Y-647136D01*
X342693Y-648336D01*
X342893Y-649536D01*
X343193Y-650336D01*
X343793Y-651136D01*
X344493Y-651669D01*
X345193Y-651936D01*
X345893D01*
X346593Y-651669D01*
X347193Y-651269D01*
X347693Y-650736D01*
G01X350993Y-651936D02*
Y-643936D01*
X352993D01*
X353793Y-644336D01*
X354393Y-644869D01*
X354893Y-645669D01*
X355293Y-646603D01*
X355393Y-647936D01*
X355293Y-649269D01*
X354893Y-650203D01*
X354393Y-651003D01*
X353793Y-651536D01*
X352993Y-651936D01*
X350993D01*
G01X361193Y-643936D02*
X360393Y-644203D01*
X359793Y-644869D01*
X359393Y-645669D01*
X359093Y-646736D01*
X358993Y-647936D01*
X359093Y-649136D01*
X359393Y-650203D01*
X359793Y-651003D01*
X360393Y-651669D01*
X361193Y-651936D01*
X361993Y-651669D01*
X362593Y-651003D01*
X362993Y-650203D01*
X363293Y-649136D01*
X363393Y-647936D01*
X363293Y-646736D01*
X362993Y-645669D01*
X362593Y-644869D01*
X361993Y-644203D01*
X361193Y-643936D01*
G01X298418Y-624819D02*
Y-618519D01*
X301394D01*
G01X300298Y-621564D02*
X298418D01*
G01X306206Y-618519D02*
X305579Y-618729D01*
X305109Y-619254D01*
X304796Y-619884D01*
X304561Y-620724D01*
X304483Y-621669D01*
X304561Y-622614D01*
X304796Y-623454D01*
X305109Y-624084D01*
X305579Y-624609D01*
X306206Y-624819D01*
X306833Y-624609D01*
X307303Y-624084D01*
X307616Y-623454D01*
X307851Y-622614D01*
X307929Y-621669D01*
X307851Y-620724D01*
X307616Y-619884D01*
X307303Y-619254D01*
X306833Y-618729D01*
X306206Y-618519D01*
G01X312506D02*
Y-624819D01*
G01X310704Y-618519D02*
X314308D01*
G01X316456Y-626919D02*
X321156D01*
G01X323069Y-624819D02*
Y-618519D01*
X325106Y-623769D01*
X327143Y-618519D01*
Y-624819D01*
G01X332816D02*
Y-620619D01*
G01Y-621354D02*
X332503Y-620934D01*
X332033Y-620724D01*
X331484Y-620619D01*
X330936Y-620829D01*
X330466Y-621249D01*
X330153Y-621879D01*
X329996Y-622719D01*
X330153Y-623559D01*
X330466Y-624189D01*
X330936Y-624609D01*
X331484Y-624819D01*
X332033Y-624714D01*
X332503Y-624399D01*
X332816Y-623979D01*
G01X336374Y-624819D02*
Y-620619D01*
G01Y-621669D02*
X336688Y-621144D01*
X337158Y-620724D01*
X337784Y-620619D01*
X338333Y-620724D01*
X338803Y-621144D01*
X339038Y-621879D01*
Y-624819D01*
G01X345416D02*
Y-620619D01*
G01Y-621354D02*
X345103Y-620934D01*
X344633Y-620724D01*
X344084Y-620619D01*
X343536Y-620829D01*
X343066Y-621249D01*
X342753Y-621879D01*
X342596Y-622719D01*
X342753Y-623559D01*
X343066Y-624189D01*
X343536Y-624609D01*
X344084Y-624819D01*
X344633Y-624714D01*
X345103Y-624399D01*
X345416Y-623979D01*
G01X349209Y-626394D02*
X349758Y-626814D01*
X350384Y-626919D01*
X350933Y-626814D01*
X351403Y-626289D01*
X351716Y-625554D01*
Y-620619D01*
G01Y-621459D02*
X351403Y-621039D01*
X350933Y-620724D01*
X350384Y-620619D01*
X349758Y-620829D01*
X349366Y-621249D01*
X349053Y-621984D01*
X348896Y-622719D01*
X348974Y-623349D01*
X349288Y-624084D01*
X349758Y-624609D01*
X350384Y-624819D01*
X350854Y-624714D01*
X351403Y-624294D01*
X351716Y-623874D01*
G01X355431Y-621984D02*
X357938D01*
X357703Y-621249D01*
X357311Y-620829D01*
X356763Y-620619D01*
X356214Y-620724D01*
X355744Y-621039D01*
X355431Y-621774D01*
X355274Y-622404D01*
Y-623034D01*
X355431Y-623664D01*
X355823Y-624294D01*
X356293Y-624714D01*
X356841Y-624819D01*
X357389Y-624609D01*
X357938Y-623979D01*
G01X360556Y-624819D02*
Y-620619D01*
G01Y-621774D02*
X360791Y-621249D01*
X361183Y-620829D01*
X361731Y-620619D01*
X362279Y-620829D01*
X362671Y-621249D01*
X362906Y-621774D01*
Y-624819D01*
G01Y-621774D02*
X363141Y-621249D01*
X363533Y-620829D01*
X364081Y-620619D01*
X364629Y-620829D01*
X365021Y-621249D01*
X365256Y-621879D01*
Y-624819D01*
G01X368031Y-621984D02*
X370538D01*
X370303Y-621249D01*
X369911Y-620829D01*
X369363Y-620619D01*
X368814Y-620724D01*
X368344Y-621039D01*
X368031Y-621774D01*
X367874Y-622404D01*
Y-623034D01*
X368031Y-623664D01*
X368423Y-624294D01*
X368893Y-624714D01*
X369441Y-624819D01*
X369989Y-624609D01*
X370538Y-623979D01*
G01X374174Y-624819D02*
Y-620619D01*
G01Y-621669D02*
X374488Y-621144D01*
X374958Y-620724D01*
X375584Y-620619D01*
X376133Y-620724D01*
X376603Y-621144D01*
X376838Y-621879D01*
Y-624819D01*
G01X381806Y-618519D02*
Y-624819D01*
G01X380709Y-620619D02*
X382903D01*
G01X385756Y-626919D02*
X390456D01*
G01X395033Y-621459D02*
X395346Y-621144D01*
X395581Y-620619D01*
X395738Y-619884D01*
X395581Y-619254D01*
X395268Y-618834D01*
X394719Y-618519D01*
X392604D01*
Y-624819D01*
X395189D01*
X395738Y-624399D01*
X396051Y-623769D01*
X396208Y-623034D01*
X396051Y-622299D01*
X395581Y-621669D01*
X395033Y-621459D01*
X392604D01*
G01X398983Y-624819D02*
Y-618519D01*
X400549D01*
X401176Y-618834D01*
X401646Y-619254D01*
X402038Y-619884D01*
X402351Y-620619D01*
X402429Y-621669D01*
X402351Y-622719D01*
X402038Y-623454D01*
X401646Y-624084D01*
X401176Y-624504D01*
X400549Y-624819D01*
X398983D01*
G01X367693Y-679936D02*
Y-671936D01*
X366493Y-673536D01*
G01Y-679936D02*
X368893D01*
G01X373793Y-676603D02*
X374493Y-675669D01*
X375093Y-675136D01*
X375893Y-674869D01*
X376593Y-675136D01*
X377093Y-675669D01*
X377493Y-676469D01*
X377593Y-677403D01*
X377493Y-678203D01*
X377093Y-679003D01*
X376493Y-679669D01*
X375793Y-679936D01*
X374993Y-679669D01*
X374293Y-678870D01*
X373893Y-677669D01*
X373793Y-676336D01*
X373993Y-674603D01*
X374293Y-673669D01*
X374793Y-672736D01*
X375493Y-672069D01*
X376193Y-671936D01*
X376893Y-672203D01*
X377393Y-672869D01*
G01X383693Y-680203D02*
X383493Y-680069D01*
Y-679803D01*
X383693Y-679669D01*
X383893Y-679803D01*
Y-680069D01*
X383693Y-680203D01*
G01X389793Y-676603D02*
X390493Y-675669D01*
X391093Y-675136D01*
X391893Y-674869D01*
X392593Y-675136D01*
X393093Y-675669D01*
X393493Y-676469D01*
X393593Y-677403D01*
X393493Y-678203D01*
X393093Y-679003D01*
X392493Y-679669D01*
X391793Y-679936D01*
X390993Y-679669D01*
X390293Y-678870D01*
X389893Y-677669D01*
X389793Y-676336D01*
X389993Y-674603D01*
X390293Y-673669D01*
X390793Y-672736D01*
X391493Y-672069D01*
X392193Y-671936D01*
X392893Y-672203D01*
X393393Y-672869D01*
G01X412693Y-679936D02*
Y-671936D01*
X411493Y-673536D01*
G01Y-679936D02*
X413893D01*
G01X420493D02*
X420693Y-678203D01*
X420993Y-676736D01*
X421393Y-675403D01*
X421893Y-673936D01*
X422693Y-671936D01*
X418693D01*
G01X428693Y-680203D02*
X428493Y-680069D01*
Y-679803D01*
X428693Y-679669D01*
X428893Y-679803D01*
Y-680069D01*
X428693Y-680203D01*
G01X434793Y-673269D02*
X435393Y-672469D01*
X436093Y-672069D01*
X436893Y-671936D01*
X437893Y-672203D01*
X438593Y-672869D01*
X438793Y-673669D01*
X438693Y-674470D01*
X438293Y-675136D01*
X436293Y-676469D01*
X435393Y-677403D01*
X434793Y-678736D01*
X434593Y-679936D01*
X438793D01*
G01X432493Y-654936D02*
Y-646936D01*
X434493D01*
X435293Y-647336D01*
X435893Y-647869D01*
X436393Y-648669D01*
X436793Y-649603D01*
X436893Y-650936D01*
X436793Y-652269D01*
X436393Y-653203D01*
X435893Y-654003D01*
X435293Y-654536D01*
X434493Y-654936D01*
X432493D01*
G54D16*
G01X-61100Y250316D02*
Y236312D01*
X-60600Y235812D01*
X-48610D01*
X-47520Y234722D01*
Y233182D01*
X-48610Y232092D01*
X-65090D01*
X-68300Y228882D01*
Y224342D01*
X-65090Y221132D01*
X-48610D01*
X-47520Y220042D01*
Y218502D01*
X-48610Y217412D01*
X-65090D01*
X-68300Y214202D01*
Y209662D01*
X-65090Y206452D01*
X-48610D01*
X-47520Y205362D01*
Y203822D01*
X-48610Y202732D01*
X-65090D01*
X-68300Y199522D01*
Y194982D01*
X-65090Y191772D01*
X-48610D01*
X-47520Y190682D01*
Y189142D01*
X-48610Y188052D01*
X-65090D01*
X-68300Y184842D01*
Y180302D01*
X-65090Y177092D01*
X-48610D01*
X-47520Y176002D01*
Y174462D01*
X-48610Y173372D01*
X-65090D01*
X-68300Y170162D01*
Y165622D01*
X-65090Y162412D01*
X-48610D01*
X-47520Y161322D01*
Y159782D01*
X-48610Y158692D01*
X-59975D01*
X-60779Y157888D01*
Y155948D01*
X-59903Y155072D01*
X-47110D01*
X-43900Y158282D01*
Y162822D01*
X-47110Y166032D01*
X-63590D01*
X-64680Y167122D01*
Y168662D01*
X-63590Y169752D01*
X-47110D01*
X-43900Y172962D01*
Y177502D01*
X-47110Y180712D01*
X-63590D01*
X-64680Y181802D01*
Y183342D01*
X-63590Y184432D01*
X-47110D01*
X-43900Y187642D01*
Y192182D01*
X-47110Y195392D01*
X-63590D01*
X-64680Y196482D01*
Y198022D01*
X-63590Y199112D01*
X-47110D01*
X-43900Y202322D01*
Y206862D01*
X-47110Y210072D01*
X-63590D01*
X-64680Y211162D01*
Y212702D01*
X-63590Y213792D01*
X-47110D01*
X-43900Y217002D01*
Y221542D01*
X-47110Y224752D01*
X-63590D01*
X-64680Y225842D01*
Y227382D01*
X-63590Y228472D01*
X-47110D01*
X-43900Y231682D01*
Y236222D01*
X-47110Y239432D01*
X-50600D01*
X-51100Y239932D01*
Y250316D01*
G01X205598Y140480D02*
Y137402D01*
X205990Y137010D01*
Y128690D01*
X204610Y127310D01*
X202203D01*
X196620Y121727D01*
Y114267D01*
X188983Y106630D01*
X171129D01*
X166539Y102040D01*
X129900D01*
X122330Y94470D01*
X116296D01*
X107826Y86000D01*
X105000D01*
X102500Y83500D01*
Y82500D01*
X97075Y77075D01*
X92076D01*
X87501Y72500D01*
X76300D01*
X74310Y70510D01*
Y64400D01*
X73810Y63900D01*
X58400D01*
X53200Y69100D01*
X51400D01*
X50300Y70200D01*
Y83004D01*
X56850Y89554D01*
Y108242D01*
X49632Y115460D01*
X29403D01*
X27213Y113270D01*
X20431D01*
X10488Y123213D01*
Y306480D01*
X21400Y317392D01*
Y332960D01*
X23834Y335394D01*
X27200D01*
X27700Y335894D01*
Y341001D01*
X25401Y343300D01*
X16448D01*
X10888Y348860D01*
Y410721D01*
X18219Y418052D01*
X24151D01*
X28633Y422534D01*
Y426667D01*
X27030Y428270D01*
Y432962D01*
X34508Y440440D01*
X66453D01*
X68460Y442447D01*
X75720D01*
X77747Y440420D01*
X82381D01*
X87900Y434901D01*
X98801D01*
X105480Y441580D01*
X142481D01*
X149910Y434151D01*
Y425350D01*
X148060Y423500D01*
G01X25202Y425329D02*
X21502D01*
X8248Y412075D01*
Y347171D01*
X18674Y336745D01*
Y318401D01*
X7848Y307575D01*
Y122118D01*
X19336Y110630D01*
X28620D01*
X30730Y112740D01*
X33540D01*
X36020Y110260D01*
Y108680D01*
X38400Y106300D01*
X46760D01*
X51455Y101605D01*
Y99051D01*
X53910Y96596D01*
Y90710D01*
X47080Y83880D01*
Y67020D01*
X48600Y65500D01*
X52000D01*
X59660Y57840D01*
X106240D01*
X114690Y66290D01*
Y78510D01*
X118380Y82200D01*
Y84979D01*
X132801Y99400D01*
X168123D01*
X168543Y98980D01*
X171581D01*
X176591Y103990D01*
X190077D01*
X199696Y113609D01*
X204491D01*
X205520Y114638D01*
Y121205D01*
X207725Y123410D01*
X209568Y124173D01*
X210420Y125448D01*
Y130601D01*
X208627Y132394D01*
G01X95770Y437920D02*
Y439030D01*
X92600Y442200D01*
Y445340D01*
X87200Y450740D01*
X79840D01*
X74187Y445087D01*
X67366D01*
X65359Y443080D01*
X24980D01*
X6928Y425028D01*
Y346624D01*
X17354Y336198D01*
Y318948D01*
X6528Y308122D01*
Y121571D01*
X18789Y109310D01*
X29800D01*
X35450Y103660D01*
X45666D01*
X48815Y100511D01*
Y97957D01*
X50980Y95792D01*
Y91680D01*
X50950Y91650D01*
Y91584D01*
X44440Y85074D01*
Y65174D01*
X47100Y62514D01*
Y50400D01*
X49700Y47800D01*
X98500D01*
X102000Y51300D01*
Y54100D01*
X103100Y55200D01*
X113200D01*
X124007Y66007D01*
Y74993D01*
X125730Y76716D01*
Y81790D01*
X137739Y93799D01*
X154585D01*
X159312Y89072D01*
X170388D01*
X172830Y86630D01*
Y75554D01*
X174320Y74064D01*
X179324D01*
X187160Y81900D01*
X192801D01*
X207901Y97000D01*
X231468D01*
X234135Y99667D01*
Y102115D01*
X232900Y103350D01*
Y107418D01*
X235230Y109748D01*
Y114534D01*
X236320Y117162D01*
Y118397D01*
X242500Y124577D01*
Y129000D01*
G01X208576Y128957D02*
X206430Y126811D01*
Y123982D01*
X204072Y121624D01*
X200924D01*
X197981Y118681D01*
Y113761D01*
X189530Y105310D01*
X176044D01*
X171034Y100300D01*
X169090D01*
X168670Y100720D01*
X131000D01*
X122580Y92300D01*
X117300D01*
X114230Y89230D01*
Y81700D01*
X113370Y80840D01*
Y66970D01*
X106300Y59900D01*
X60000D01*
X52200Y67700D01*
X49300D01*
X48400Y68600D01*
Y83000D01*
X55450Y90050D01*
Y103448D01*
X54199Y104699D01*
X51886D01*
X46535Y110050D01*
X40534D01*
X36444Y114140D01*
X29950D01*
X27760Y111950D01*
X19884D01*
X9168Y122666D01*
Y307027D01*
X19994Y317853D01*
Y337293D01*
X9568Y347719D01*
Y411268D01*
X17773Y419473D01*
X23705D01*
X27313Y423081D01*
Y426119D01*
X25710Y427722D01*
Y433509D01*
X33961Y441760D01*
X65906D01*
X67913Y443767D01*
X76432D01*
X78459Y441740D01*
X84544D01*
X89020Y441731D01*
X92920Y437831D01*
X92870D01*
G01X45500Y92500D02*
X42190D01*
X26980Y107710D01*
X18390D01*
X5208Y120892D01*
Y308669D01*
X16034Y319495D01*
Y335651D01*
X5608Y346077D01*
Y425608D01*
X24400Y444400D01*
X64812D01*
X66819Y446407D01*
X73607D01*
X79260Y452060D01*
X87747D01*
X92167Y447640D01*
X103900D01*
G01X59240Y67242D02*
X62100Y70102D01*
Y76700D01*
X58170Y80630D01*
Y108789D01*
X50179Y116780D01*
X31300D01*
X29460Y118620D01*
X16948D01*
X11926Y123642D01*
Y306051D01*
X22995Y317120D01*
X26610D01*
X27700Y318210D01*
Y332200D01*
X31000Y335500D01*
Y342500D01*
G01X143000Y414600D02*
Y433800D01*
X136540Y440260D01*
X106027D01*
X99348Y433581D01*
X87320D01*
X81801Y439100D01*
X77199D01*
X75172Y441127D01*
X69687D01*
X67680Y439120D01*
X39283D01*
X33910Y433747D01*
Y432050D01*
X33400Y431540D01*
Y425201D01*
X24830Y416631D01*
X18665D01*
X17300Y415266D01*
Y415265D01*
X16960Y414925D01*
Y404561D01*
X15840Y403441D01*
Y396433D01*
X14220Y394813D01*
Y364687D01*
X16180Y362727D01*
Y361127D01*
X17260Y360047D01*
Y354760D01*
X17300Y354720D01*
Y347467D01*
X19767Y345000D01*
X31500D01*
X33000Y343500D01*
Y335000D01*
X29020Y331020D01*
Y322680D01*
X33000Y318700D01*
G01X35500Y335000D02*
X36000Y335500D01*
X36500D01*
X38000Y337000D01*
Y342500D01*
X37000Y343500D01*
X35100D01*
X31600Y347000D01*
Y348633D01*
X26799Y353434D01*
X20453D01*
X18580Y355307D01*
Y360640D01*
X18534D01*
X17500Y361674D01*
Y363274D01*
X15540Y365234D01*
Y394266D01*
X17160Y395886D01*
Y402894D01*
X18280Y404014D01*
Y414378D01*
X19181Y415279D01*
X25479D01*
X34720Y424520D01*
Y430790D01*
X37630Y433700D01*
X40000D01*
X42200Y435900D01*
G01X48420Y321616D02*
X48155D01*
X45700Y319161D01*
Y316100D01*
X44700Y315100D01*
X38100D01*
X36750Y316450D01*
Y330490D01*
X39450Y333190D01*
Y345300D01*
X36250Y348500D01*
X33600D01*
X27345Y354755D01*
X26253D01*
X26252Y354754D01*
X21000D01*
X19900Y355854D01*
Y361187D01*
X19600Y361487D01*
Y363041D01*
X16860Y365781D01*
Y393719D01*
X18480Y395339D01*
Y402347D01*
X19600Y403467D01*
Y413428D01*
X20100Y413928D01*
X25995D01*
X36040Y423973D01*
Y430243D01*
X37787Y431990D01*
X55667D01*
Y435160D01*
X58127Y437620D01*
X69211D01*
X71391Y439800D01*
X74400D01*
X76580Y437620D01*
X79580D01*
X84320Y432880D01*
Y430510D01*
G01X35100Y352400D02*
X31568D01*
X27900Y356068D01*
Y360392D01*
X25013Y363279D01*
X21229D01*
X18180Y366328D01*
Y393172D01*
X19800Y394792D01*
Y401800D01*
X21600Y403600D01*
X29250D01*
X31550Y405900D01*
Y410694D01*
X38678Y417822D01*
Y428122D01*
X38000Y428800D01*
G01X187700Y99000D02*
X185750Y97050D01*
X179777D01*
X174447Y91720D01*
X158531D01*
X155132Y95119D01*
X130387D01*
X121390Y86122D01*
Y82800D01*
X120545Y81955D01*
Y65545D01*
X111520Y56520D01*
X55220D01*
X51430Y60310D01*
X49790D01*
X49086Y61014D01*
Y62774D01*
X45760Y66100D01*
Y84460D01*
X52520Y91220D01*
Y96119D01*
X50135Y98504D01*
Y101058D01*
X46213Y104980D01*
X37310D01*
X31890Y110400D01*
G01X182108Y129094D02*
Y127896D01*
X173352Y119140D01*
X146990D01*
X145006Y117156D01*
X138544D01*
X129900Y125800D01*
X119500D01*
X112970Y132330D01*
Y138698D01*
X108468Y143200D01*
X99498D01*
X94085Y148613D01*
Y157636D01*
X76431Y175290D01*
X71030D01*
X68700Y177620D01*
Y181803D01*
X63491Y187012D01*
Y189692D01*
X65576Y191777D01*
Y192685D01*
X67931Y195040D01*
Y196492D01*
X68790Y197351D01*
Y202846D01*
X64263Y207373D01*
Y230717D01*
X65990Y232444D01*
Y247890D01*
X70800Y252700D01*
Y261215D01*
X69740Y262275D01*
X68725D01*
X64400Y266600D01*
Y279699D01*
X63099Y281000D01*
Y288721D01*
X55740Y296080D01*
Y306706D01*
X58077Y309043D01*
Y316104D01*
X58600Y316627D01*
Y326633D01*
X46700Y338533D01*
Y360600D01*
X45490Y361810D01*
X43510D01*
X39200Y357500D01*
X33900D01*
X32900Y358500D01*
Y361844D01*
X29430Y365314D01*
Y394671D01*
X33697Y398938D01*
Y400698D01*
X42609Y409610D01*
X49340D01*
X50520Y410790D01*
Y414101D01*
X51679Y415260D01*
X58493D01*
X60253Y417020D01*
X62080D01*
X67713Y422653D01*
X69030D01*
G01X199985Y132294D02*
Y131353D01*
X197960Y129328D01*
Y125359D01*
X195000Y122399D01*
Y114939D01*
X188311Y108250D01*
X164334D01*
X159784Y103700D01*
X145900D01*
X142900Y106700D01*
X131850D01*
X121900Y96750D01*
X116284D01*
X107534Y88000D01*
X104500D01*
X100700Y84200D01*
Y83116D01*
X96279Y78695D01*
X62506D01*
X59790Y81411D01*
Y109461D01*
X59600Y109651D01*
Y109652D01*
X56200Y113052D01*
Y179449D01*
X44237Y191412D01*
X44210Y191452D01*
X44200Y191502D01*
Y196008D01*
X44180Y196028D01*
Y208172D01*
X44200Y208192D01*
Y218443D01*
X46500Y223996D01*
Y240100D01*
X46000Y240600D01*
Y260801D01*
X49420Y264221D01*
Y315480D01*
X48600Y316300D01*
Y318601D01*
X50790Y320791D01*
Y322911D01*
X47801Y325900D01*
X43000D01*
X42390Y326510D01*
Y349109D01*
X39510Y351989D01*
Y353450D01*
X38450Y354510D01*
X31751D01*
X29600Y356661D01*
Y360985D01*
X25685Y364900D01*
X21900D01*
X19800Y367000D01*
Y392500D01*
X21600Y394300D01*
X24900D01*
X30757Y400157D01*
Y401917D01*
X33170Y404330D01*
Y410022D01*
X41348Y418200D01*
X57234D01*
X62000Y422966D01*
Y426992D01*
X57287Y431705D01*
Y434488D01*
X58799Y436000D01*
X78600D01*
X82510Y432090D01*
Y429760D01*
X83570Y428700D01*
X85070D01*
X86840Y430470D01*
X99663D01*
X100793Y431600D01*
X106100D01*
X109047Y428653D01*
Y425854D01*
X109048Y425853D01*
G01X44525Y360000D02*
X40655Y356130D01*
X32458D01*
X31400Y357188D01*
Y361477D01*
X28110Y364767D01*
Y395218D01*
X32377Y399485D01*
Y401245D01*
X34790Y403658D01*
Y409350D01*
X42020Y416580D01*
X57906D01*
X63900Y422574D01*
Y423760D01*
X68740Y428600D01*
X81378D01*
X82899Y427079D01*
X84241D01*
X84242Y427080D01*
X85742D01*
X87512Y428850D01*
X100335D01*
X101465Y429980D01*
X105428D01*
X107100Y428308D01*
Y425000D01*
X108057Y424043D01*
X121662D01*
X121700Y424005D01*
G01X40340Y100710D02*
X45785D01*
X47178Y99317D01*
Y97727D01*
X49630Y95275D01*
Y92131D01*
X40988Y83489D01*
Y51012D01*
X45590Y46410D01*
X111510D01*
X115200Y50100D01*
Y55200D01*
X125440Y65440D01*
Y74559D01*
X127581Y76700D01*
X132625D01*
X136575Y80650D01*
X143526D01*
X144646Y81770D01*
X158043D01*
X161999Y77814D01*
Y72320D01*
X166315Y68004D01*
X181835D01*
X189671Y75840D01*
X195416D01*
X196926Y77350D01*
X208267D01*
X217317Y86400D01*
X228230D01*
X232150Y82480D01*
G01X190744Y114456D02*
Y112975D01*
X187639Y109870D01*
X163662D01*
X159192Y105400D01*
X146970D01*
X143900Y108470D01*
X129070D01*
X122100Y101500D01*
X115179D01*
X109589Y95910D01*
X104910D01*
X102540Y93540D01*
X99000Y84996D01*
Y83708D01*
X95607Y80315D01*
X66584D01*
X61500Y85399D01*
Y110044D01*
X57820Y113724D01*
Y180122D01*
X54520Y183422D01*
Y192470D01*
X53650Y193340D01*
X49160D01*
X45800Y196700D01*
Y207500D01*
X45820Y207520D01*
Y218120D01*
X48300Y224106D01*
Y240899D01*
X47700Y241499D01*
Y244283D01*
X48412Y244995D01*
X55288D01*
X56000Y245707D01*
Y246713D01*
X55288Y247425D01*
X48412D01*
X47700Y248137D01*
Y251782D01*
X48412Y252494D01*
X51288D01*
X52000Y253206D01*
Y254212D01*
X51288Y254924D01*
X48412D01*
X47700Y255636D01*
Y260101D01*
X52600Y265001D01*
Y268391D01*
X53165Y268956D01*
X54635D01*
X55200Y269521D01*
Y270321D01*
X54635Y270886D01*
X53165D01*
X52600Y271451D01*
Y272251D01*
X53165Y272816D01*
X54635D01*
X55200Y273381D01*
Y274181D01*
X54635Y274746D01*
X53165D01*
X52600Y275311D01*
Y276111D01*
X53165Y276676D01*
X54635D01*
X55200Y277241D01*
Y278041D01*
X54635Y278606D01*
X53165D01*
X52600Y279171D01*
Y279971D01*
X53165Y280536D01*
X54635D01*
X55200Y281101D01*
Y281901D01*
X54635Y282466D01*
X53165D01*
X51110Y284521D01*
Y316090D01*
X50950Y316250D01*
Y318050D01*
G01X109670Y136060D02*
X105641D01*
X101321Y140380D01*
X100309D01*
X92765Y147924D01*
Y156968D01*
X84863Y164870D01*
X67300D01*
X65520Y166650D01*
Y181248D01*
X60851Y185917D01*
Y190786D01*
X62936Y192871D01*
Y193779D01*
X65291Y196134D01*
Y197586D01*
X66150Y198445D01*
Y201752D01*
X61623Y206279D01*
Y231497D01*
X58040Y235080D01*
Y236580D01*
X62060Y240600D01*
Y250407D01*
X63000Y251347D01*
Y264280D01*
X59290Y267990D01*
Y282811D01*
X54420Y287681D01*
Y307253D01*
X56757Y309590D01*
Y315283D01*
X54790Y317250D01*
Y326110D01*
X52140Y328760D01*
X44481D01*
G01X35100Y352400D02*
X40770Y346730D01*
Y325830D01*
X42718Y323882D01*
Y317600D01*
X43218Y317100D01*
X43500D01*
G01X37300Y375000D02*
X42390Y369910D01*
X46475D01*
X49800Y366585D01*
Y348900D01*
X50700Y348000D01*
X57500D01*
X59300Y346200D01*
Y340500D01*
X64810Y334990D01*
Y312125D01*
X61437Y308752D01*
Y307305D01*
X58080Y303948D01*
Y297073D01*
X71810Y283343D01*
Y279109D01*
X67760Y275059D01*
Y269083D01*
X74170Y262673D01*
Y250741D01*
X73011Y249582D01*
Y246365D01*
G01X68757Y374733D02*
X67247Y373223D01*
X62277D01*
X56800Y378700D01*
X50000D01*
X49300Y378000D01*
X40900D01*
X38000Y380900D01*
Y384620D01*
X37020Y385600D01*
G01X44500Y380000D02*
Y381464D01*
X35100Y390864D01*
Y400234D01*
X43156Y408290D01*
X50989D01*
X56639Y413940D01*
X59040D01*
X60800Y415700D01*
X62627D01*
X64152Y417225D01*
X70325D01*
X73500Y420400D01*
X84990D01*
X92120Y427530D01*
X100882D01*
X102012Y428660D01*
X104657D01*
X105700Y427617D01*
Y424500D01*
X110525Y419675D01*
X122498D01*
G01X37735Y391200D02*
X41032Y394497D01*
Y401302D01*
X43420Y403690D01*
X64735D01*
X67900Y400525D01*
G01X44330Y401450D02*
X53010D01*
X55710Y398750D01*
Y384320D01*
X63750Y376280D01*
X69740D01*
X70390Y375630D01*
Y371000D01*
X67240Y367850D01*
Y345650D01*
X68350Y344540D01*
Y327870D01*
X70390Y325830D01*
Y322160D01*
X67980Y319750D01*
Y311410D01*
X66440Y309870D01*
Y305420D01*
X64230Y303210D01*
G01X196577Y141185D02*
X193610Y138218D01*
Y123310D01*
X188911Y118611D01*
Y113434D01*
X186967Y111490D01*
X162990D01*
X158700Y107200D01*
X147900D01*
X145010Y110090D01*
X128398D01*
X125308Y107000D01*
X109415D01*
X103955Y101540D01*
X97380Y85667D01*
Y84380D01*
X94935Y81935D01*
X67764D01*
X64320Y85379D01*
Y131380D01*
X65612Y132672D01*
Y160622D01*
X63900Y162334D01*
Y180576D01*
X59231Y185245D01*
Y191458D01*
X61316Y193543D01*
Y194451D01*
X62210Y195345D01*
Y201900D01*
X60003Y204107D01*
Y209790D01*
X56100Y213693D01*
Y218600D01*
X58500Y221000D01*
Y232328D01*
X56420Y234408D01*
Y237252D01*
X58700Y239532D01*
Y251668D01*
X57105Y253263D01*
X55065D01*
X54500Y253828D01*
Y254628D01*
X55065Y255193D01*
X57105D01*
X57670Y255758D01*
Y256558D01*
X57105Y257123D01*
X55065D01*
X54500Y257688D01*
Y258488D01*
X55065Y259053D01*
X57105D01*
X57670Y259618D01*
Y260418D01*
X57105Y260983D01*
X55065D01*
X54500Y261548D01*
Y262348D01*
X55065Y262913D01*
X57105D01*
X57670Y263478D01*
Y264278D01*
X57105Y264843D01*
X55065D01*
X54500Y265408D01*
Y266208D01*
X55065Y266773D01*
X57105D01*
X57670Y267338D01*
Y282030D01*
X52800Y286900D01*
Y322400D01*
G01X59850Y235830D02*
X62943Y232737D01*
Y206826D01*
X67470Y202299D01*
Y197898D01*
X66611Y197039D01*
Y195587D01*
X64256Y193232D01*
Y192324D01*
X62171Y190239D01*
Y186464D01*
X67150Y181485D01*
Y172008D01*
X70158Y169000D01*
X74349D01*
X76442Y166907D01*
G01X57400Y345400D02*
X58280Y344520D01*
Y330263D01*
X61190Y327353D01*
Y322510D01*
X62730Y320970D01*
Y311488D01*
X60417Y309175D01*
Y307728D01*
X57060Y304371D01*
Y296650D01*
X67930Y285780D01*
Y281187D01*
X66740Y279997D01*
Y268660D01*
X73150Y262250D01*
Y251460D01*
X68580Y246890D01*
Y232790D01*
X69960Y231410D01*
Y227853D01*
X66603Y224496D01*
Y210153D01*
X70110Y206646D01*
Y202390D01*
X71600Y200900D01*
G01X77437Y262760D02*
X70100Y270097D01*
Y273989D01*
X74150Y278039D01*
Y285351D01*
X76199Y287400D01*
X79320D01*
X81020Y289100D01*
Y291858D01*
X79878Y293000D01*
X75110D01*
X72860Y290750D01*
X66270D01*
X59400Y297620D01*
Y303401D01*
X62757Y306758D01*
Y308205D01*
X66500Y311948D01*
Y337590D01*
X65120Y338970D01*
Y347180D01*
X63300Y349000D01*
X60200D01*
X55500Y353700D01*
Y365900D01*
X51600Y369800D01*
Y373800D01*
X52500Y374700D01*
X54400D01*
G01X134400Y127652D02*
X133145Y127650D01*
X120150D01*
X115320Y132480D01*
Y139660D01*
X107050Y147930D01*
X105658D01*
X77426Y176162D01*
X76851Y177549D01*
X75410Y178990D01*
X74534D01*
X74524Y179000D01*
X73883D01*
X69336Y183547D01*
Y189936D01*
X74060Y194660D01*
Y205583D01*
X68643Y211000D01*
Y223650D01*
X75460Y230467D01*
Y231469D01*
X84680Y240689D01*
Y250620D01*
X79300Y256000D01*
Y263457D01*
X78187Y264570D01*
X77494D01*
X72000Y270064D01*
Y273500D01*
X80410Y281910D01*
Y286411D01*
X82340Y288341D01*
Y292405D01*
X80425Y294320D01*
X74439D01*
X70667Y298092D01*
X67540Y305645D01*
Y309480D01*
X69590Y311530D01*
Y318430D01*
X70460Y319300D01*
X82100D01*
X83500Y320700D01*
Y336200D01*
X86107Y338807D01*
Y351214D01*
X87617Y352724D01*
G01X178284Y132394D02*
X176370Y130480D01*
Y127920D01*
X169080Y120630D01*
X146120D01*
X144067Y118577D01*
X139223D01*
X137040Y120760D01*
Y128230D01*
X135470Y129800D01*
X133399D01*
X132599Y129000D01*
X131001D01*
X117871Y142130D01*
X114717D01*
X107597Y149250D01*
X106205D01*
X79715Y175740D01*
X77110Y182029D01*
Y184625D01*
X75856Y185879D01*
Y187240D01*
X75710Y187386D01*
Y192474D01*
X77332Y194096D01*
Y199172D01*
X78830Y200670D01*
Y231529D01*
X89160Y241859D01*
Y248060D01*
X93110Y252010D01*
Y254222D01*
X92532Y254800D01*
X87800D01*
X86100Y256500D01*
Y262302D01*
X85400Y263002D01*
Y280573D01*
X87530Y282703D01*
Y285196D01*
X92733Y290399D01*
Y304457D01*
X92490Y304700D01*
Y311750D01*
X94200Y313460D01*
Y318032D01*
X90340Y321892D01*
Y328204D01*
X89400Y329144D01*
Y332356D01*
X90340Y333296D01*
Y346040D01*
X92406Y348106D01*
Y351214D01*
X93916Y352724D01*
G01X100500Y328547D02*
X99610Y327657D01*
Y323787D01*
X96570Y320747D01*
Y305510D01*
X94053Y302993D01*
Y289852D01*
X88850Y284649D01*
Y282156D01*
X86780Y280086D01*
Y263711D01*
X86800Y263691D01*
Y263469D01*
X87420Y262849D01*
Y257047D01*
X88347Y256120D01*
X93079D01*
X94430Y254769D01*
Y251463D01*
X90480Y247513D01*
Y237637D01*
X80150Y227307D01*
Y200123D01*
X78652Y198625D01*
Y193549D01*
X77030Y191927D01*
Y188176D01*
X77565Y186885D01*
X78995Y185455D01*
X81500Y179405D01*
Y176515D01*
G01X74583Y217314D02*
X72393D01*
X70690Y215611D01*
Y210820D01*
X75850Y205660D01*
Y194583D01*
X73180Y191913D01*
Y187356D01*
X74046Y186490D01*
G01X78770Y290708D02*
Y290678D01*
X76982Y288890D01*
X75822D01*
X72830Y285898D01*
Y278586D01*
X68780Y274536D01*
Y269506D01*
X75190Y263096D01*
Y252410D01*
X78300Y249300D01*
Y245760D01*
X74440Y241900D01*
Y230890D01*
X67623Y224073D01*
Y210577D01*
X72150Y206050D01*
Y204810D01*
G01X76670Y208772D02*
X77510Y209612D01*
Y232076D01*
X85700Y240266D01*
Y251043D01*
X80320Y256423D01*
Y263880D01*
X78800Y265400D01*
Y273040D01*
X79710Y273950D01*
Y279610D01*
X81620Y281520D01*
Y286178D01*
X83360Y287918D01*
Y292828D01*
X80848Y295340D01*
X74862D01*
X71720Y298482D01*
X70582Y301231D01*
Y306352D01*
X71970Y307740D01*
Y311370D01*
X71000Y312340D01*
Y316280D01*
X73000Y318280D01*
X85182D01*
X87700Y320798D01*
Y327110D01*
X86760Y328050D01*
Y333450D01*
X87700Y334390D01*
Y347521D01*
X89127Y348948D01*
Y356499D01*
X88243Y357383D01*
X82865D01*
X81355Y355873D01*
G01X99990Y311200D02*
X99620D01*
X97890Y309470D01*
Y304829D01*
X95690Y302629D01*
Y289090D01*
X90170Y283570D01*
Y282703D01*
X90171Y282702D01*
Y281610D01*
X88100Y279539D01*
Y264036D01*
X95750Y256386D01*
Y250916D01*
X91800Y246966D01*
Y237090D01*
X81470Y226760D01*
Y199576D01*
X79972Y198078D01*
Y193002D01*
X78400Y191430D01*
Y188319D01*
X78684Y187633D01*
X81888Y184429D01*
X87012Y172059D01*
X107181Y151890D01*
X108691D01*
X115811Y144770D01*
X119831D01*
X129601Y135000D01*
X135500D01*
G01Y138000D02*
Y138700D01*
X123460Y150740D01*
X111708D01*
X109238Y153210D01*
X107728D01*
X88411Y172527D01*
X84760Y181343D01*
Y198140D01*
X83810Y200434D01*
Y225790D01*
X94270Y236250D01*
Y241717D01*
X98130Y245577D01*
Y257316D01*
X93310Y262136D01*
Y279106D01*
X95130Y280926D01*
Y283930D01*
X98030Y286830D01*
Y292230D01*
X99400Y293600D01*
X100700D01*
G01X113000Y160700D02*
X107706D01*
X92891Y175515D01*
X90070Y182328D01*
Y199560D01*
X89090Y201929D01*
Y223601D01*
X101650Y236161D01*
Y243496D01*
X102090Y243936D01*
Y258957D01*
X100307Y260740D01*
Y264617D01*
X98920Y266004D01*
Y278219D01*
X101990Y281289D01*
Y288596D01*
X105150Y291756D01*
Y300449D01*
X106910Y302209D01*
Y316540D01*
X104870Y318580D01*
Y325610D01*
X103630Y326850D01*
Y331177D01*
X103130Y331677D01*
X96327D01*
X94300Y333704D01*
Y341200D01*
X97500Y344400D01*
X101340D01*
X103365Y346425D01*
G01X103000Y323800D02*
X103160Y323640D01*
Y302909D01*
X102510Y302259D01*
Y292850D01*
X99350Y289690D01*
Y282939D01*
X94630Y278219D01*
Y262683D01*
X99450Y257863D01*
Y245030D01*
X95590Y241170D01*
Y235703D01*
X85130Y225243D01*
Y201011D01*
X86080Y198717D01*
Y181606D01*
X89530Y173275D01*
X108275Y154530D01*
X109785D01*
X112255Y152060D01*
X125227D01*
X131267Y158100D01*
X133690D01*
G01X176550Y125210D02*
X177555D01*
X180100Y127755D01*
Y133138D01*
X178224Y135014D01*
X173954D01*
X172530Y133590D01*
Y131200D01*
X171390Y130060D01*
X169430D01*
X168560Y130930D01*
Y133349D01*
X160159Y141750D01*
X145640D01*
X144350Y143040D01*
Y147010D01*
X143110Y148250D01*
X139630D01*
X138700Y149180D01*
Y159390D01*
X136650Y161440D01*
X120440D01*
X115075Y156075D01*
X111974D01*
X110879Y157170D01*
X109369D01*
X91769Y174770D01*
X88750Y182062D01*
Y199297D01*
X87770Y201666D01*
Y224148D01*
X98720Y235098D01*
Y236980D01*
G01X105100Y309300D02*
Y302450D01*
X103830Y301180D01*
Y292303D01*
X100670Y289143D01*
Y282071D01*
X97600Y279001D01*
Y265457D01*
X98987Y264070D01*
Y260193D01*
X100770Y258410D01*
Y244483D01*
X96910Y240623D01*
Y235156D01*
X86450Y224696D01*
Y201276D01*
X87400Y198983D01*
Y181869D01*
X90649Y174023D01*
X108822Y155850D01*
X110332D01*
X112802Y153380D01*
X124680D01*
X131300Y160000D01*
X134350D01*
X136190Y158160D01*
Y158100D01*
G01X110900Y378500D02*
X107725Y375325D01*
Y365775D01*
X109810Y363690D01*
X112750D01*
X113510Y362930D01*
Y356460D01*
X112250Y355200D01*
Y346250D01*
X107800Y341800D01*
X97710D01*
X95660Y339750D01*
Y334570D01*
X97180Y333050D01*
X104300D01*
X108800Y328550D01*
Y301210D01*
X106620Y299030D01*
Y290910D01*
X103310Y287600D01*
Y279960D01*
X100420Y277070D01*
Y266420D01*
X103650Y263190D01*
Y248960D01*
X106700Y245910D01*
Y234030D01*
X90820Y218150D01*
Y202210D01*
X92820Y200210D01*
Y180825D01*
X94980Y175610D01*
X106970Y163620D01*
X136870D01*
X143085Y157405D01*
Y155045D01*
X145840Y152290D01*
Y144740D01*
X147405Y143175D01*
X160765D01*
X170610Y133330D01*
Y131900D01*
G01X90766Y352724D02*
X92342Y354300D01*
X94800D01*
X95426Y353674D01*
Y346826D01*
X92980Y344380D01*
Y333157D01*
X95780Y330357D01*
X101810D01*
X102310Y329857D01*
Y327210D01*
X100930Y325830D01*
Y318350D01*
X101840Y317440D01*
Y310150D01*
X101830Y310140D01*
Y303920D01*
X97010Y299100D01*
Y287811D01*
X94110Y284911D01*
Y281350D01*
X89600Y276840D01*
Y264403D01*
X97110Y256893D01*
Y246000D01*
X93250Y242140D01*
Y236673D01*
X82790Y226213D01*
Y197430D01*
X82370Y197010D01*
G01X90766Y349574D02*
Y348366D01*
X89020Y346620D01*
Y333843D01*
X88080Y332903D01*
Y328597D01*
X89020Y327657D01*
Y321100D01*
X90810Y319310D01*
Y296530D01*
X85200Y290920D01*
Y287600D01*
X82940Y285340D01*
Y280973D01*
X81030Y279063D01*
Y273403D01*
X80120Y272493D01*
Y265947D01*
X81640Y264427D01*
Y256970D01*
X85703Y252907D01*
X87187D01*
X91300Y252900D01*
G01X92698Y323224D02*
X91660Y324262D01*
Y328751D01*
X90720Y329691D01*
Y331809D01*
X91660Y332749D01*
Y345360D01*
X93916Y347616D01*
Y349574D01*
G01X111330Y357800D02*
X108710D01*
X98200Y368310D01*
Y378980D01*
X97780Y379400D01*
X92696D01*
X92276Y379820D01*
Y381659D01*
X91392Y382543D01*
X79716D01*
X78206Y381033D01*
G01X123120Y213088D02*
X123119Y213089D01*
Y217797D01*
X118805Y228216D01*
Y231877D01*
X116350Y234332D01*
Y241010D01*
X115780Y241580D01*
Y250180D01*
X116054Y250454D01*
Y254468D01*
X119490Y257904D01*
Y270270D01*
X118260Y271500D01*
Y279622D01*
X117370Y280512D01*
Y285944D01*
X118749Y287323D01*
Y302952D01*
X116199Y305502D01*
Y332860D01*
X117410Y334071D01*
Y356289D01*
X117160Y356539D01*
Y362640D01*
X112600Y367200D01*
X110400D01*
X108900Y368700D01*
Y373300D01*
X112610Y377010D01*
Y382490D01*
X108640Y386460D01*
Y391260D01*
X105909Y393991D01*
Y410991D01*
X104567Y412333D01*
X103733D01*
X102267Y410867D01*
Y408007D01*
X99560Y405300D01*
X92622D01*
X89487Y408435D01*
G01X95845Y424755D02*
Y422945D01*
X92800Y419900D01*
X89400D01*
X84801Y415301D01*
Y409760D01*
G01X161900Y150500D02*
X161170Y149770D01*
X157131D01*
X155901Y151000D01*
X148671D01*
X145270Y154401D01*
Y157563D01*
X140073Y162760D01*
X139442D01*
X137012Y165190D01*
X122730D01*
X120500Y167420D01*
Y194620D01*
X116965Y198155D01*
Y206715D01*
X118600Y208350D01*
Y215665D01*
X118085Y218254D01*
X117137Y220543D01*
X107720Y229960D01*
Y247783D01*
X104790Y250713D01*
Y267494D01*
X105646Y268350D01*
Y279100D01*
X106574Y280028D01*
G01X99026Y338368D02*
Y337880D01*
X102430Y334476D01*
X105023D01*
X110150Y329349D01*
Y303390D01*
X113160Y300380D01*
Y290210D01*
X111600Y288650D01*
Y284000D01*
G01X103180Y336286D02*
X105413D01*
X111470Y330229D01*
Y304630D01*
X114789Y301311D01*
Y288964D01*
X113409Y287584D01*
Y284304D01*
X113410Y284303D01*
Y281277D01*
X109020Y276887D01*
Y272010D01*
X112160Y268870D01*
Y264850D01*
X113780Y263230D01*
Y260610D01*
X109040Y255870D01*
Y230690D01*
X118283Y221447D01*
X119386Y218784D01*
X119990Y215748D01*
Y207409D01*
X121208Y206191D01*
Y198150D01*
X122720Y196638D01*
Y188110D01*
X123860Y186970D01*
Y173840D01*
X127750Y169950D01*
X134120D01*
X138580Y165490D01*
X139210D01*
X146590Y158110D01*
Y154948D01*
X149218Y152320D01*
X163062D01*
X163710Y151672D01*
Y142624D01*
X168590Y137744D01*
X179213D01*
X184230Y132727D01*
Y128151D01*
X173859Y117780D01*
X163140D01*
X162657Y117297D01*
G01X100457Y409100D02*
Y410557D01*
X104200Y414300D01*
X120000D01*
X124500Y418800D01*
Y424005D01*
G01X146300Y161010D02*
X140198Y167112D01*
X139258D01*
X134755Y171615D01*
X132315D01*
X128830Y175100D01*
Y186100D01*
X124860Y190070D01*
Y196818D01*
X122528Y199150D01*
Y206738D01*
X121310Y207956D01*
Y217191D01*
X120000Y221512D01*
X116866Y226202D01*
X113312Y229756D01*
Y232401D01*
X114000Y233089D01*
Y233760D01*
X114010Y233770D01*
Y236290D01*
X114800Y237080D01*
Y240290D01*
X111680Y243410D01*
Y247947D01*
X114684Y250951D01*
Y255324D01*
X117180Y257820D01*
Y264000D01*
X115978Y265202D01*
X115590Y266139D01*
Y269330D01*
X116830Y270570D01*
Y276680D01*
X116050Y277460D01*
Y285397D01*
X116049Y285398D01*
Y286490D01*
X117429Y287870D01*
Y302405D01*
X114110Y305724D01*
Y333810D01*
X115535Y335235D01*
G01X126153Y199079D02*
X126589Y199515D01*
Y212087D01*
X120262Y227365D01*
Y232571D01*
X119307Y233526D01*
Y235677D01*
X120450Y236820D01*
Y246724D01*
X117074Y250100D01*
Y254044D01*
X123900Y260870D01*
Y271140D01*
X122160Y272880D01*
Y291911D01*
X120600Y293471D01*
G01X137196Y274491D02*
Y274151D01*
X132310Y269265D01*
Y260109D01*
X130001Y257800D01*
X127600D01*
X126810Y257010D01*
Y251110D01*
X125600Y249900D01*
Y242500D01*
X123350Y240250D01*
Y233650D01*
X121500Y231800D01*
Y227043D01*
X128000Y211348D01*
Y190560D01*
X130750Y187810D01*
Y175850D01*
X133590Y173010D01*
X136390D01*
X137650Y174270D01*
X140970D01*
X142580Y172660D01*
Y168380D01*
X144240Y166720D01*
X156240D01*
X165700Y157260D01*
Y152172D01*
X168686Y149186D01*
Y145286D01*
X170977Y142995D01*
X205643D01*
X207440Y141198D01*
Y138000D01*
X207860Y137580D01*
Y137021D01*
X212727Y132154D01*
G01X112200Y234520D02*
X110360Y236360D01*
Y248494D01*
X113284Y251418D01*
Y255884D01*
X115560Y258160D01*
Y263752D01*
X114859Y264453D01*
X114000Y266527D01*
Y271379D01*
X113190Y273338D01*
Y279189D01*
X114730Y280729D01*
Y284850D01*
X114729Y284851D01*
Y287037D01*
X116109Y288417D01*
Y301858D01*
X112790Y305177D01*
Y344090D01*
X114700Y346000D01*
Y348500D01*
G01X119105Y251511D02*
X119611D01*
X120000Y251900D01*
X123400D01*
X125210Y253710D01*
Y260020D01*
X126648Y261458D01*
Y268018D01*
X132420Y273790D01*
Y273811D01*
G01X128866Y433066D02*
Y432104D01*
X131559Y429411D01*
Y428817D01*
X128304Y425562D01*
Y419071D01*
X125590Y416357D01*
Y410126D01*
X122437Y406973D01*
Y404984D01*
X114060Y396607D01*
Y385240D01*
X115520Y383780D01*
Y375899D01*
X117319Y374100D01*
Y370620D01*
X120529Y367410D01*
X122291D01*
X124680Y365021D01*
Y357207D01*
X119800Y352327D01*
Y331211D01*
X120520Y330491D01*
Y322149D01*
X121229Y321440D01*
X123401D01*
X124110Y320731D01*
Y319729D01*
X123401Y319020D01*
X121229D01*
X120520Y318311D01*
Y316602D01*
X121620Y315502D01*
Y308190D01*
X126230Y303580D01*
Y289637D01*
X132924Y282943D01*
X137024D01*
X140280Y279687D01*
X140326Y279589D01*
Y273817D01*
X139885Y272753D01*
X134850Y267718D01*
Y253522D01*
X128600Y247272D01*
Y241600D01*
X127366Y240366D01*
Y221300D01*
X130340Y214116D01*
Y198288D01*
X135465Y185911D01*
Y183425D01*
X133690Y181650D01*
Y178810D01*
X135400Y177100D01*
X140604D01*
X146324Y171380D01*
X149194D01*
X152534Y168040D01*
X156787D01*
X167020Y157807D01*
Y152719D01*
X170006Y149733D01*
Y145833D01*
X171524Y144315D01*
X206585D01*
X209180Y141720D01*
Y138250D01*
X211410Y136020D01*
X214780D01*
X216600Y134200D01*
X227490D01*
X229396Y132294D01*
G01X135300Y175100D02*
X132370Y178030D01*
Y182197D01*
X132600Y182427D01*
Y189378D01*
X129020Y198022D01*
Y213852D01*
X126046Y221034D01*
Y241146D01*
X127200Y242300D01*
Y249000D01*
X131190Y252990D01*
Y256850D01*
X133330Y258990D01*
Y268065D01*
X138729Y273464D01*
X139006Y274110D01*
Y279094D01*
X136477Y281623D01*
X132377D01*
X124910Y289090D01*
Y303033D01*
X120300Y307643D01*
Y314955D01*
X119200Y316055D01*
Y329943D01*
X118700Y330443D01*
Y330444D01*
X118430Y330714D01*
Y352824D01*
X123360Y357754D01*
Y361080D01*
X118975Y365465D01*
X116434D01*
X113199Y368700D01*
X111601D01*
X110320Y369981D01*
Y371920D01*
X114200Y375800D01*
Y383100D01*
X112740Y384560D01*
Y397154D01*
X121117Y405531D01*
Y407520D01*
X124270Y410673D01*
Y416904D01*
X126984Y419618D01*
Y424556D01*
X123170Y428370D01*
Y433200D01*
G01X135350Y433016D02*
Y430740D01*
X129624Y425014D01*
Y418524D01*
X126910Y415810D01*
Y406325D01*
X115380Y394795D01*
Y385940D01*
X119220Y382100D01*
Y374440D01*
X118639Y373859D01*
Y371239D01*
X121148Y368730D01*
X123010D01*
X126000Y365740D01*
Y356660D01*
X121120Y351780D01*
Y331758D01*
X121840Y331038D01*
Y324960D01*
X128870Y317930D01*
Y290731D01*
X134018Y285583D01*
X138118D01*
X142474Y281228D01*
X142966Y280181D01*
Y273286D01*
X142125Y271256D01*
X137490Y266621D01*
Y252428D01*
X136050Y250988D01*
Y232650D01*
X136168Y232532D01*
Y229318D01*
X133081Y226231D01*
Y223919D01*
X133900Y223100D01*
X135660D01*
X136810Y221950D01*
Y220449D01*
X134320Y217959D01*
Y210180D01*
X137270Y207230D01*
Y204610D01*
X136843Y204183D01*
Y192942D01*
X139946Y185452D01*
Y183255D01*
X142400Y180801D01*
Y179596D01*
X142401Y179038D01*
X147419Y174020D01*
X149534D01*
X150954Y175440D01*
X153428D01*
X169720Y159148D01*
Y153831D01*
X174296Y149255D01*
X174682Y148677D01*
X177902Y146955D01*
X214100D01*
X215200Y145855D01*
Y139900D01*
X217780Y137320D01*
X231381D01*
X236950Y131751D01*
Y125490D01*
X234500Y123040D01*
Y117500D01*
G01X124935Y324900D02*
X125362Y325327D01*
Y329383D01*
X122590Y332155D01*
Y347090D01*
X124300Y348800D01*
G01X125650Y368650D02*
X124250Y370050D01*
X121696D01*
X120237Y371509D01*
Y373367D01*
X121100Y374230D01*
Y382087D01*
X116700Y386487D01*
Y394248D01*
X131090Y408638D01*
Y413190D01*
X132500Y414600D01*
Y415654D01*
X132490Y415664D01*
Y417164D01*
X132500Y417174D01*
Y418884D01*
X131260Y420124D01*
Y424783D01*
X137650Y431173D01*
Y435540D01*
X134250Y438940D01*
X115740D01*
X111510Y434710D01*
G01X119200Y389700D02*
X120500D01*
X124300Y385900D01*
Y373680D01*
X127460Y370520D01*
Y355260D01*
X126830Y354630D01*
Y344930D01*
X123690Y341790D01*
Y333609D01*
X127500Y329799D01*
Y326060D01*
X127510Y326050D01*
Y324550D01*
X127500Y324540D01*
Y322301D01*
X130190Y319611D01*
Y291278D01*
X134565Y286903D01*
X138665D01*
X143571Y281998D01*
X144286Y280476D01*
Y273023D01*
X143207Y270417D01*
X140090Y267300D01*
Y257500D01*
X141280Y256310D01*
G01X161237Y181735D02*
X160705D01*
X156896Y185544D01*
X152301D01*
X151241Y186604D01*
Y188104D01*
X156200Y193063D01*
Y200400D01*
X154400Y202200D01*
Y205500D01*
X150000Y209900D01*
Y213693D01*
X151200Y216591D01*
Y221739D01*
X151520Y222059D01*
Y231953D01*
X149101Y234372D01*
X146580Y240457D01*
Y245480D01*
X147900Y246800D01*
Y248600D01*
X147440Y249060D01*
Y258700D01*
X145910Y260230D01*
Y270824D01*
X146626Y272554D01*
Y280999D01*
X145516Y283364D01*
X139635Y289243D01*
X135535D01*
X132530Y292248D01*
Y300365D01*
X140924Y308759D01*
X141760D01*
X141761Y308760D01*
X142640D01*
X143700Y309820D01*
Y311400D01*
X138500Y316600D01*
X135993D01*
X132700Y319893D01*
Y327300D01*
X128150Y331850D01*
Y354083D01*
X129020Y354953D01*
Y370828D01*
X125700Y374148D01*
Y379500D01*
X129020Y382820D01*
Y387340D01*
X123950Y392410D01*
X122148D01*
X121122Y393436D01*
X120700Y394455D01*
Y395900D01*
X131020Y406220D01*
X133280D01*
X136200Y409140D01*
Y417184D01*
X134905Y418479D01*
Y421679D01*
X133572Y423012D01*
Y423935D01*
G01X147500Y289405D02*
X141341D01*
X140182Y290563D01*
X136082D01*
X133850Y292795D01*
Y299818D01*
X141471Y307439D01*
X143186D01*
X145020Y309273D01*
Y311947D01*
X139047Y317920D01*
X136540D01*
X134400Y320060D01*
Y327499D01*
X129470Y332429D01*
Y353036D01*
X129620Y353186D01*
Y353686D01*
X131190Y355256D01*
Y370526D01*
X127020Y374696D01*
Y378952D01*
X130340Y382272D01*
Y392360D01*
X126900Y395800D01*
X123800D01*
X122600Y394600D01*
G01X235001Y156599D02*
Y155799D01*
X256266Y134534D01*
Y130619D01*
X253089Y127442D01*
Y122810D01*
X254943Y120956D01*
Y114343D01*
X252010Y111410D01*
X249367D01*
X244179Y106222D01*
X243647Y104938D01*
X242800Y104091D01*
Y98940D01*
X240120Y96260D01*
X236442D01*
X232750Y92568D01*
Y91290D01*
X229880Y88420D01*
X216480D01*
X207430Y79370D01*
X196089D01*
X194579Y77860D01*
X188834D01*
X180998Y70024D01*
X167152D01*
X164110Y73066D01*
Y78560D01*
X158880Y83790D01*
X143808D01*
X142688Y82670D01*
X135738D01*
X132168Y79100D01*
X130670D01*
X129300Y80470D01*
Y82650D01*
G01X145100Y87400D02*
X144561D01*
X141851Y84690D01*
X134900D01*
X131470Y81260D01*
G01X133690Y158100D02*
Y154610D01*
X135310Y152990D01*
Y145490D01*
X140860Y139940D01*
X151290D01*
X151790Y139440D01*
Y134840D01*
X154020Y132610D01*
X159100D01*
X160640Y131070D01*
X162381D01*
X162419Y131032D01*
G01X137900Y179160D02*
X137000Y180060D01*
Y185660D01*
X131680Y198504D01*
Y214459D01*
X128690Y221684D01*
Y226431D01*
X132545Y235742D01*
Y249350D01*
X136170Y252975D01*
Y267171D01*
X141008Y272009D01*
X141646Y273551D01*
Y279885D01*
X141377Y280458D01*
X137571Y284263D01*
X133471D01*
X127550Y290184D01*
Y304127D01*
X124100Y307577D01*
Y311100D01*
G01X226887Y117297D02*
X227720Y118130D01*
Y120153D01*
X228762Y121195D01*
Y126100D01*
X231206Y128544D01*
Y133044D01*
X228530Y135720D01*
X217230D01*
X213680Y139270D01*
Y144280D01*
X212325Y145635D01*
X177571D01*
X173766Y147669D01*
X173421Y148185D01*
X168400Y153206D01*
Y158601D01*
X152881Y174120D01*
X151502D01*
X150082Y172700D01*
X146872D01*
X140800Y178772D01*
Y180401D01*
X138626Y182575D01*
Y185187D01*
X133000Y198771D01*
Y215171D01*
X130200Y221928D01*
Y224466D01*
X130765Y225031D01*
Y227566D01*
X133268Y230069D01*
X134358D01*
G01X206692Y156599D02*
X200067Y149974D01*
X180760D01*
X176706Y154028D01*
Y154075D01*
X175822Y154959D01*
X174699D01*
X173600Y156058D01*
Y160666D01*
X153896Y180370D01*
X151410Y181400D01*
X144200D01*
X141266Y184334D01*
Y185715D01*
X138597Y192160D01*
Y207771D01*
X135640Y210728D01*
Y217140D01*
X138130Y219630D01*
Y222498D01*
X137000Y223628D01*
Y228200D01*
X137488Y228688D01*
Y233788D01*
X139810Y236110D01*
Y252280D01*
X143090Y255560D01*
Y257879D01*
X144590Y259379D01*
Y271088D01*
X145306Y272818D01*
Y280704D01*
X144419Y282594D01*
X139088Y287923D01*
X134988D01*
X131210Y291701D01*
Y301210D01*
X140570Y310570D01*
X141890D01*
G01X149215Y267745D02*
X149280Y267810D01*
X150790D01*
X152230Y269250D01*
Y281690D01*
X149862Y284058D01*
Y287340D01*
X150630Y288108D01*
Y289608D01*
X150631Y289609D01*
Y290701D01*
X148797Y292535D01*
X141945D01*
X141277Y293203D01*
X138737D01*
X136778Y295162D01*
Y298978D01*
X142599Y304799D01*
X144280D01*
X147760Y308279D01*
Y312941D01*
X138580Y322121D01*
Y335020D01*
X136600Y337000D01*
X134100D01*
X132300Y338800D01*
Y349790D01*
X132600Y350090D01*
G01X138987Y423935D02*
Y418907D01*
X137600Y417520D01*
Y402800D01*
X137100Y402300D01*
X134900D01*
X133000Y400400D01*
Y396198D01*
X133500Y395698D01*
Y394090D01*
X131660Y392250D01*
Y378559D01*
X132510Y377709D01*
Y364690D01*
X134910Y362290D01*
Y356609D01*
X130790Y352489D01*
Y333010D01*
X136000Y327800D01*
Y320327D01*
X137087Y319240D01*
X138500D01*
X138501Y319241D01*
X139593D01*
X146340Y312494D01*
Y308726D01*
X143733Y306119D01*
X142018D01*
X135170Y299271D01*
Y293342D01*
X136629Y291883D01*
X140730D01*
X141398Y291215D01*
X148250D01*
X149310Y290155D01*
Y288655D01*
X147820Y287165D01*
Y281571D01*
X147946Y281303D01*
Y271571D01*
X147330Y270083D01*
Y262880D01*
X148760Y261450D01*
Y249740D01*
X150300Y248200D01*
Y246900D01*
X147900Y244500D01*
Y240720D01*
X150220Y235120D01*
X152840Y232500D01*
Y220900D01*
X155600Y218140D01*
Y215660D01*
X155610Y215650D01*
Y214150D01*
X155600Y214140D01*
Y207300D01*
X159400Y203500D01*
Y193703D01*
X153051Y187354D01*
G01X142300Y336700D02*
X139100Y339900D01*
Y342240D01*
X136230Y345110D01*
Y362838D01*
X133830Y365238D01*
Y378258D01*
X132980Y379108D01*
Y386880D01*
X135682Y389582D01*
Y395238D01*
X134820Y396100D01*
Y399420D01*
X135300Y399900D01*
G01X158750Y284949D02*
X155850Y287849D01*
Y294636D01*
X152103Y298383D01*
Y316243D01*
X152100Y316246D01*
Y316899D01*
X146700Y322299D01*
Y337900D01*
X144310Y340290D01*
Y347390D01*
X137900Y353800D01*
Y353874D01*
X137550Y354224D01*
Y363386D01*
X135150Y365786D01*
Y378806D01*
X134300Y379656D01*
Y386200D01*
X137002Y388902D01*
Y398602D01*
X137900Y399500D01*
G01X150820Y387325D02*
X136924D01*
X135320Y385721D01*
Y380080D01*
X136170Y379230D01*
Y366630D01*
X141500Y361300D01*
X142000D01*
X147075Y356225D01*
Y342252D01*
X151730Y337597D01*
Y326930D01*
X156810Y321850D01*
Y320350D01*
X154740Y318280D01*
Y317340D01*
X154743Y317337D01*
Y299479D01*
X158600Y295622D01*
Y289667D01*
X161880Y286387D01*
Y283213D01*
X156190Y277523D01*
Y266903D01*
X154140Y264853D01*
Y253300D01*
X156263Y251177D01*
Y245364D01*
X160330Y241297D01*
Y238263D01*
X158930Y236863D01*
Y233403D01*
X155480Y229953D01*
Y221994D01*
X158240Y219234D01*
Y216754D01*
X158250Y216744D01*
Y213056D01*
X158240Y213046D01*
Y209004D01*
X163500Y203744D01*
Y197200D01*
X169700Y191000D01*
X175441D01*
X178346Y188095D01*
G01X140730Y72600D02*
X144390D01*
X154416Y62574D01*
X196267D01*
X204863Y71170D01*
X236493D01*
X238096Y72773D01*
X242617D01*
X244270Y71120D01*
X253550D01*
X257800Y75370D01*
Y82800D01*
G01X235001Y153449D02*
Y146899D01*
X235710Y146190D01*
X237771D01*
X238480Y145481D01*
Y144479D01*
X237771Y143770D01*
X235710D01*
X235001Y143061D01*
Y141923D01*
X239184Y137740D01*
X250203D01*
X254246Y133697D01*
Y131456D01*
X251069Y128279D01*
Y121769D01*
X250370Y121070D01*
Y115270D01*
X242310Y107210D01*
X241815Y106015D01*
X238820Y103020D01*
Y99690D01*
X237760Y98630D01*
X235955D01*
X232305Y94980D01*
X227760D01*
X227051Y94271D01*
Y91289D01*
X226342Y90580D01*
X225340D01*
X224631Y91289D01*
Y94271D01*
X223922Y94980D01*
X216320D01*
X211580Y90240D01*
X203998D01*
X203277Y89519D01*
Y88517D01*
X207986Y83808D01*
Y82806D01*
X207276Y82096D01*
X206274D01*
X201565Y86805D01*
X200563D01*
X193638Y79880D01*
X187997D01*
X180161Y72044D01*
X173483D01*
X168280Y77247D01*
Y78249D01*
X170755Y80724D01*
Y81726D01*
X170045Y82436D01*
X169043D01*
X166568Y79961D01*
X165566D01*
X164856Y80671D01*
Y81673D01*
X168395Y85212D01*
Y85806D01*
X167277Y86924D01*
X166683D01*
X165569Y85810D01*
X149822D01*
X148232Y87400D01*
X145100D01*
G01X171700Y156900D02*
X171240Y157360D01*
Y159495D01*
X153975Y176760D01*
X147623D01*
X146882Y177501D01*
G01X140830Y192530D02*
X141800Y193500D01*
Y194900D01*
X142300Y195400D01*
Y196680D01*
X142720Y197100D01*
X148600D01*
X150100Y198600D01*
Y204500D01*
X147400Y207200D01*
Y214400D01*
X149500Y216500D01*
Y231300D01*
X144900Y235900D01*
Y247402D01*
X145580Y248082D01*
G01X144280Y195130D02*
X145203Y194207D01*
X147200Y189386D01*
Y185218D01*
X149289Y183129D01*
X150276Y182720D01*
X151845D01*
X154522Y181611D01*
X160123Y176010D01*
X161740Y175340D01*
X176502Y160578D01*
X176836Y159772D01*
Y156296D01*
X177211Y155390D01*
X180286Y152315D01*
X182751Y151294D01*
X194622D01*
X201583Y154177D01*
X206692Y159286D01*
Y159748D01*
G01X153100Y234800D02*
Y250200D01*
X151500Y251800D01*
Y265948D01*
X153550Y267998D01*
Y279649D01*
X154400Y280499D01*
Y290085D01*
X152895Y291590D01*
X151650D01*
X150300Y292940D01*
Y299550D01*
X148000Y301850D01*
Y306652D01*
X149080Y307732D01*
Y313488D01*
X139900Y322668D01*
Y334300D01*
X142300Y336700D01*
G01X149862Y243788D02*
X151700Y245626D01*
Y249000D01*
X150080Y250620D01*
Y266880D01*
X149215Y267745D01*
G01X141000Y358500D02*
X142933D01*
X145755Y355678D01*
Y341705D01*
X150410Y337050D01*
Y326170D01*
X153130Y323450D01*
Y318967D01*
X153125Y318955D01*
X153420Y318660D01*
Y316793D01*
X153423Y316790D01*
Y298931D01*
X157170Y295184D01*
Y289230D01*
X160560Y285840D01*
Y283760D01*
X154870Y278070D01*
Y267450D01*
X152820Y265400D01*
Y252600D01*
X154830Y250590D01*
Y244930D01*
X159010Y240750D01*
Y238810D01*
X157610Y237410D01*
Y233952D01*
X157609Y233949D01*
X154160Y230500D01*
Y221447D01*
X156920Y218687D01*
Y216207D01*
X156930Y216197D01*
Y213603D01*
X156920Y213593D01*
Y207981D01*
X160900Y204001D01*
Y193200D01*
X158277Y190577D01*
Y186083D01*
X160815Y183545D01*
X166155D01*
X169500Y180200D01*
G01X138700Y376600D02*
X147900D01*
X150430Y374070D01*
Y364727D01*
X153800Y361357D01*
Y352300D01*
X150840Y349340D01*
Y339930D01*
X152750Y338020D01*
Y327353D01*
X157830Y322273D01*
Y319927D01*
X155760Y317857D01*
Y317763D01*
X155763Y317760D01*
Y299903D01*
X159620Y296046D01*
Y290090D01*
X162900Y286810D01*
Y282790D01*
X159840Y279730D01*
Y267440D01*
X158780Y266380D01*
Y259790D01*
X155160Y256170D01*
Y254100D01*
X157585Y251675D01*
Y245485D01*
X161350Y241720D01*
Y236011D01*
X163010Y234351D01*
Y232783D01*
X161927Y231700D01*
X159000D01*
X156500Y229200D01*
Y222417D01*
X159270Y219647D01*
Y210630D01*
X163650Y206250D01*
Y205750D01*
X167400Y202000D01*
Y198800D01*
X170600Y195600D01*
X175426D01*
X176706Y196880D01*
Y202165D01*
X178346Y203805D01*
G01X171836Y200655D02*
Y203721D01*
X169280Y206277D01*
Y211739D01*
X166608Y214411D01*
X161879D01*
X160290Y216000D01*
Y220070D01*
X157520Y222840D01*
Y228777D01*
X159423Y230680D01*
X162350D01*
X164030Y232360D01*
Y234774D01*
X162370Y236434D01*
Y242143D01*
X158780Y245733D01*
Y256230D01*
X162430Y259880D01*
Y264020D01*
X160860Y265590D01*
Y279202D01*
X164300Y282642D01*
Y292810D01*
X156783Y300327D01*
Y317437D01*
X158850Y319504D01*
Y322696D01*
X155229Y326317D01*
Y361371D01*
X151450Y365150D01*
Y377750D01*
X152100Y378400D01*
G01X158246Y78872D02*
X160500Y76618D01*
Y71952D01*
X165768Y66684D01*
X183924D01*
X189760Y72520D01*
X195220D01*
X203187Y75820D01*
X210683D01*
X214231Y79368D01*
X233348D01*
X239194Y85214D01*
X262157D01*
X265000Y88057D01*
Y95007D01*
X268105Y98112D01*
Y107643D01*
X259967Y115781D01*
Y120739D01*
X257172Y123534D01*
Y126354D01*
X260200Y129382D01*
Y132395D01*
G01X156710Y73420D02*
Y70590D01*
X163706Y63594D01*
X195844D01*
X205150Y72900D01*
X211893D01*
X215441Y76448D01*
X240328D01*
X242460Y78580D01*
X251920D01*
X253000Y77500D01*
G01X152500Y382600D02*
X154100Y381000D01*
Y363943D01*
X156249Y361794D01*
Y326740D01*
X159870Y323119D01*
Y319081D01*
X157803Y317014D01*
Y300750D01*
X165320Y293233D01*
Y282219D01*
X161880Y278779D01*
Y273020D01*
X166721Y268179D01*
Y259921D01*
X163200Y256400D01*
Y243900D01*
X165500Y241600D01*
Y236100D01*
G01X181495Y197506D02*
X180994D01*
X179900Y198600D01*
Y211300D01*
X179456Y211744D01*
X177456D01*
X176706Y212494D01*
Y214694D01*
X175900Y215500D01*
X173257D01*
X170500Y218257D01*
Y223252D01*
X170106Y223646D01*
X168830Y226732D01*
Y259579D01*
X168762Y259647D01*
Y269574D01*
X166846Y271490D01*
Y280859D01*
X167360Y281373D01*
Y294079D01*
X164220Y297219D01*
Y304059D01*
X163373Y304906D01*
Y309127D01*
X160000Y312500D01*
Y315400D01*
X161910Y317310D01*
Y323965D01*
X161880Y323995D01*
Y349019D01*
X158720Y352179D01*
Y362323D01*
X158700Y362343D01*
Y376600D01*
X156390Y378910D01*
Y382900D01*
X152630Y386660D01*
Y396030D01*
X155452Y398852D01*
Y401000D01*
G01X171836Y198300D02*
X172400D01*
X173546Y199446D01*
Y203454D01*
X170300Y206700D01*
Y212240D01*
X168590Y213950D01*
Y215450D01*
X169100Y215960D01*
Y223409D01*
X167741Y226696D01*
Y268739D01*
X165826Y270654D01*
Y281282D01*
X166340Y281796D01*
Y293656D01*
X163200Y296796D01*
Y303636D01*
X162262Y304574D01*
X160326D01*
X158823Y306077D01*
Y316591D01*
X160890Y318658D01*
Y323542D01*
X160860Y323572D01*
Y347540D01*
X157700Y350700D01*
Y361900D01*
X156300Y363300D01*
Y376300D01*
G01X172400Y220700D02*
Y222797D01*
X170970Y224227D01*
Y225171D01*
X169850Y227884D01*
Y260751D01*
X169782Y260819D01*
Y264763D01*
X170600Y265581D01*
Y279367D01*
X169420Y280547D01*
Y292923D01*
X169401Y292942D01*
Y294924D01*
X166260Y298065D01*
Y304905D01*
X166070Y305095D01*
Y311669D01*
X167500Y313099D01*
Y316656D01*
X166600Y317556D01*
Y352000D01*
X167800Y353200D01*
Y373000D01*
X159400Y381400D01*
X158200D01*
G01X165501Y382800D02*
X167050Y381251D01*
Y381250D01*
X172900Y375400D01*
Y341982D01*
X172908Y341974D01*
Y340474D01*
X172900Y340466D01*
Y336900D01*
X168590Y332590D01*
Y312389D01*
X167090Y310889D01*
Y306010D01*
X168600Y304500D01*
Y303400D01*
X169960Y302040D01*
X170080D01*
X170500Y301620D01*
Y286220D01*
X174787Y281933D01*
Y275285D01*
X171955Y272453D01*
Y266805D01*
X173260Y265500D01*
X174934D01*
X176180Y264254D01*
Y262256D01*
X170870Y256946D01*
Y228087D01*
X171990Y225384D01*
Y224650D01*
X173050Y223590D01*
X175410D01*
X178000Y221000D01*
Y215736D01*
X181000Y212736D01*
Y211200D01*
X183100Y209100D01*
Y199900D01*
X183980Y199020D01*
X185480D01*
X186300Y198200D01*
Y198148D01*
X186284Y198132D01*
Y196880D01*
X186300Y196864D01*
Y190600D01*
X185400Y189700D01*
X183100D01*
X181495Y188095D01*
G01X165500Y386000D02*
X167600Y383900D01*
Y382499D01*
X174080Y376019D01*
Y352320D01*
X174100Y352300D01*
Y321103D01*
X173170Y320173D01*
Y316714D01*
X170170Y313714D01*
Y311231D01*
X172422Y308979D01*
Y303582D01*
X175807Y300197D01*
Y274861D01*
X173489Y272543D01*
Y268388D01*
X177200Y264677D01*
Y261833D01*
X171890Y256523D01*
Y228290D01*
X172584Y226616D01*
X173800Y225400D01*
G01X162100Y414000D02*
Y398799D01*
X171620Y389279D01*
Y381664D01*
X182560Y370724D01*
Y365286D01*
X176540Y359266D01*
Y327224D01*
X178400Y325364D01*
Y317800D01*
X176533Y315933D01*
Y314049D01*
G01X158100Y442700D02*
X162969Y437831D01*
Y433300D01*
X161200Y431531D01*
Y420000D01*
X165600Y415600D01*
Y398599D01*
X173040Y391159D01*
Y382253D01*
X184360Y370933D01*
Y356567D01*
X177960Y350167D01*
Y327813D01*
X181300Y324473D01*
Y302001D01*
X184493Y298808D01*
Y279460D01*
X179770Y274737D01*
Y271031D01*
X180980Y269821D01*
Y263663D01*
X181400Y262648D01*
Y262503D01*
X182300Y260330D01*
Y258208D01*
X181541Y254391D01*
X180480Y251830D01*
Y237257D01*
X183031Y234706D01*
Y231613D01*
X184645Y229999D01*
Y229002D01*
G01X160700Y445550D02*
X163570D01*
X177700Y431420D01*
Y429100D01*
X187590Y419210D01*
Y416010D01*
X194500Y409100D01*
Y402600D01*
G01X221278Y132294D02*
X219200Y130216D01*
Y126600D01*
X211500Y118900D01*
X210140D01*
X209560Y118320D01*
Y114440D01*
X210200Y113800D01*
Y111200D01*
X208100Y109100D01*
X200902D01*
X194500Y102698D01*
Y95400D01*
X191700Y92600D01*
X188000D01*
X186559Y91159D01*
Y90157D01*
X187467Y89249D01*
Y88247D01*
X186757Y87537D01*
X185755D01*
X184847Y88445D01*
X183845D01*
X178200Y82800D01*
Y76145D01*
G01X212727Y129654D02*
X214610Y127771D01*
Y124882D01*
X211231Y121503D01*
X209776Y120900D01*
X208300D01*
X207540Y120140D01*
Y113801D01*
X205239Y111500D01*
X200445D01*
X192347Y103402D01*
Y96292D01*
X190855Y94800D01*
X187143D01*
X175700Y83357D01*
Y76245D01*
G01X289600Y322253D02*
X288645Y323208D01*
X285846D01*
X280065Y317427D01*
Y315507D01*
X274510Y309952D01*
Y303962D01*
X273280Y302732D01*
Y292614D01*
X272330Y291664D01*
Y263329D01*
X260191Y251190D01*
X257990D01*
X255000Y248200D01*
Y246500D01*
X252400Y243900D01*
X242100D01*
X237000Y238800D01*
Y233500D01*
X239700Y230800D01*
Y221800D01*
X238963Y221063D01*
X237524D01*
X236640Y220179D01*
Y219039D01*
X235601Y218000D01*
X226200D01*
X222964Y214764D01*
X218627D01*
X217743Y213880D01*
Y212443D01*
X215321Y210021D01*
Y207822D01*
X214501Y207002D01*
Y206301D01*
X213515Y205315D01*
X212115D01*
X208332Y201532D01*
Y200132D01*
X205052Y196852D01*
Y190400D01*
X201852Y187200D01*
X196900D01*
X194900Y185200D01*
X194000D01*
X192105Y183305D01*
X190205D01*
X189304Y182404D01*
Y181169D01*
X188420Y180285D01*
X187185D01*
X186284Y179384D01*
Y178149D01*
X185271Y177136D01*
X184137D01*
X183135Y176134D01*
Y174836D01*
X182285Y173986D01*
X180998D01*
X179985Y172973D01*
Y165421D01*
X180869Y164537D01*
X182563D01*
X184202Y162898D01*
X184645D01*
G01X286372Y326768D02*
X285830Y326226D01*
X281826D01*
X278805Y323205D01*
Y316029D01*
X273250Y310474D01*
Y304484D01*
X272020Y303254D01*
Y293136D01*
X270790Y291906D01*
Y277096D01*
X266890Y273196D01*
Y271551D01*
X264600Y269261D01*
Y267900D01*
X265200Y267300D01*
Y264009D01*
X261591Y260400D01*
X259999D01*
X255300Y255701D01*
Y252200D01*
X253200Y250100D01*
X252082D01*
X250759Y248777D01*
Y246657D01*
X249602Y245500D01*
X241834D01*
X235800Y239466D01*
Y232200D01*
X237600Y230400D01*
Y227900D01*
X236640Y226940D01*
Y222140D01*
X235693Y221193D01*
X224793D01*
X223950Y220350D01*
Y218450D01*
X221600Y216100D01*
X218700D01*
X216700Y214100D01*
Y212800D01*
X214501Y210601D01*
Y209478D01*
X213523Y208500D01*
X208800D01*
X208300Y208000D01*
Y206300D01*
X205000Y203000D01*
X203000D01*
X202000Y202000D01*
Y189500D01*
X201100Y188600D01*
X196900D01*
X194800Y186500D01*
X190363D01*
X189434Y185571D01*
Y184334D01*
X188405Y183305D01*
X187168D01*
X186155Y182292D01*
Y181169D01*
X185271Y180285D01*
X183885D01*
X183005Y179405D01*
Y178020D01*
X181991Y177006D01*
X180706D01*
X179856Y176156D01*
Y174870D01*
X178972Y173986D01*
X177849D01*
X176836Y172973D01*
Y166764D01*
X179856Y163744D01*
Y162272D01*
X180828Y161300D01*
X182800D01*
X184352Y159748D01*
X184645D01*
G01X235000Y335300D02*
X234550Y334850D01*
Y316950D01*
X236620Y314880D01*
X238626D01*
X239700Y313806D01*
Y306600D01*
X243300Y303000D01*
Y301982D01*
X242588Y301270D01*
X236612D01*
X235900Y300558D01*
Y299552D01*
X236612Y298840D01*
X242588D01*
X243300Y298128D01*
Y297122D01*
X242588Y296410D01*
X236612D01*
X235900Y295698D01*
Y294692D01*
X236612Y293980D01*
X242588D01*
X243300Y293268D01*
Y292262D01*
X242588Y291550D01*
X236612D01*
X235900Y290838D01*
Y289832D01*
X236612Y289120D01*
X242588D01*
X243300Y288408D01*
Y286539D01*
X244012Y285827D01*
X245388D01*
X246100Y285115D01*
Y284109D01*
X245388Y283397D01*
X244012D01*
X243300Y282685D01*
Y279641D01*
X242200Y276986D01*
Y274800D01*
X245200Y271800D01*
Y264764D01*
X244488Y264052D01*
X242912D01*
X242200Y263340D01*
Y262334D01*
X242912Y261622D01*
X244488D01*
X245200Y260910D01*
Y254000D01*
X242800Y251600D01*
X237700D01*
X234900Y248800D01*
Y244200D01*
X231200Y240500D01*
Y238300D01*
X229900Y237000D01*
Y231900D01*
X231200Y230600D01*
X232400D01*
X233500Y229500D01*
Y225300D01*
X232500Y224300D01*
X221800D01*
X220892Y223392D01*
Y219056D01*
X218936Y217100D01*
X218400D01*
X214501Y213201D01*
Y212628D01*
X213573Y211700D01*
X208800D01*
X205100Y208000D01*
Y205400D01*
X203900Y204200D01*
X202400D01*
X200400Y202200D01*
Y195300D01*
X198800Y193700D01*
Y190401D01*
X198099Y189700D01*
X189200D01*
X186200Y186700D01*
Y183900D01*
X185700Y183400D01*
X184000D01*
X183100Y182500D01*
Y181000D01*
X182256Y180156D01*
X180456D01*
X171100Y170800D01*
Y168008D01*
X177720Y161388D01*
X179112D01*
X179900Y160600D01*
Y155044D01*
X181495Y153449D01*
G01X189054Y397500D02*
X186900Y395346D01*
Y386460D01*
X185490Y385050D01*
Y375311D01*
X187780Y373021D01*
Y354724D01*
X185610Y352554D01*
Y342000D01*
X184182Y340572D01*
Y325027D01*
X182700Y321449D01*
Y302801D01*
X185813Y299688D01*
Y278912D01*
X181200Y274299D01*
Y271900D01*
X182300Y270800D01*
Y263926D01*
X183235Y261669D01*
X183233Y261667D01*
X183518Y260983D01*
X183671Y260613D01*
X183678Y260595D01*
X183700Y260490D01*
Y258477D01*
X183698Y258449D01*
X183689Y258365D01*
X183684Y258332D01*
X182789Y253830D01*
X182781Y253800D01*
X182753Y253708D01*
X182742Y253676D01*
X181800Y251400D01*
Y237804D01*
X186089Y233515D01*
X186138Y233450D01*
X186158Y233404D01*
X186167Y233366D01*
X186170Y233330D01*
Y202180D01*
X184645Y200655D01*
G01X178346Y229002D02*
X179460Y230116D01*
Y241141D01*
X177944Y242657D01*
Y258871D01*
X179900Y260827D01*
Y269401D01*
X178750Y270551D01*
Y275390D01*
X181080Y277720D01*
Y280520D01*
X179100Y282500D01*
Y289449D01*
X179260Y289609D01*
Y303980D01*
X171190Y312050D01*
Y313290D01*
X174190Y316290D01*
Y319750D01*
X175120Y320680D01*
Y352723D01*
X175100Y352743D01*
Y360000D01*
X177500Y362400D01*
Y369100D01*
G01X175300Y240000D02*
X178640Y236660D01*
Y232030D01*
X176750Y230140D01*
Y228450D01*
X177730Y227470D01*
X182407D01*
X183077Y226800D01*
Y218622D01*
X184645Y217054D01*
Y213254D01*
G01Y156599D02*
X185599D01*
X187109Y158109D01*
X194809D01*
X195733Y159033D01*
Y166673D01*
X197600Y168540D01*
Y170000D01*
X198980Y171380D01*
X201820D01*
X203440Y173000D01*
X206332D01*
X208332Y175000D01*
Y176122D01*
X211481Y179271D01*
Y182421D01*
X212365Y183305D01*
X213605D01*
X216000Y185700D01*
Y191213D01*
X220783Y195996D01*
X237596D01*
X240700Y199100D01*
X266189D01*
X275073Y202780D01*
X283480Y211187D01*
Y215598D01*
X293660Y225778D01*
Y271741D01*
X289281Y276120D01*
X284280D01*
X282911Y277489D01*
Y279569D01*
G01X286372Y320700D02*
X282165Y316493D01*
Y314637D01*
X276610Y309082D01*
Y303092D01*
X275400Y301882D01*
Y289420D01*
X274430Y288450D01*
Y260784D01*
X264483Y250838D01*
X264482Y250836D01*
X263851Y250205D01*
X262591Y247161D01*
X257230Y241800D01*
X248500D01*
X245700Y239000D01*
Y234370D01*
X245280Y233950D01*
X243950D01*
X242900Y232900D01*
Y221640D01*
X238440Y217180D01*
X232580D01*
X230200Y214800D01*
X226500D01*
X223314Y211614D01*
X218414D01*
X216500Y209700D01*
Y207500D01*
X215600Y206600D01*
Y204200D01*
X213565Y202165D01*
X212365D01*
X211481Y201281D01*
Y193881D01*
X207000Y189400D01*
X205500D01*
X199300Y183200D01*
X194500D01*
X191700Y180400D01*
X191685D01*
X191570Y180285D01*
X190285D01*
X189304Y179304D01*
Y178020D01*
X188420Y177136D01*
X188336D01*
X188300Y177100D01*
X187300D01*
X187206Y177006D01*
X187168D01*
X186155Y175993D01*
Y174675D01*
X185480Y174000D01*
X185285D01*
X185271Y173986D01*
X183986D01*
X183100Y173100D01*
Y165456D01*
X184019Y164537D01*
X185663D01*
X187302Y162898D01*
X187794D01*
G01X290120Y339370D02*
X293680Y335810D01*
Y321280D01*
X291500Y319100D01*
X289673D01*
X285560Y314987D01*
Y308278D01*
X279970Y302688D01*
Y301700D01*
X278800Y300530D01*
Y287800D01*
X277790Y286790D01*
Y259391D01*
X267333Y248934D01*
X263293Y239177D01*
X259440Y235322D01*
Y219222D01*
X256318Y216100D01*
X240300D01*
X238600Y214400D01*
X233500D01*
X230300Y211200D01*
Y207900D01*
X227800Y205400D01*
X218700D01*
X217743Y204443D01*
Y202643D01*
X215580Y200480D01*
Y194880D01*
X201212Y180512D01*
Y177912D01*
X200306Y177006D01*
X196617D01*
X194600Y174989D01*
Y173300D01*
X192007Y170707D01*
X190318D01*
X189434Y169823D01*
Y166534D01*
X188947Y166047D01*
X187794D01*
G01X190944Y162898D02*
X190202D01*
X188600Y164500D01*
X187200D01*
X186600Y165100D01*
Y165105D01*
X186200Y165505D01*
Y169800D01*
X187100Y170700D01*
X187161D01*
X187168Y170707D01*
X188420D01*
X189304Y171591D01*
Y172973D01*
X189300Y172977D01*
Y173100D01*
X190100Y173900D01*
X192100D01*
X193400Y175200D01*
Y176939D01*
X196617Y180156D01*
X199256D01*
X214760Y195660D01*
Y201860D01*
X216700Y203800D01*
Y205100D01*
X217743Y206143D01*
Y207581D01*
X218627Y208465D01*
X220235D01*
X228044Y211700D01*
X229400D01*
X233500Y215800D01*
X238500D01*
X239900Y217200D01*
X242700D01*
X245600Y220100D01*
Y227100D01*
X249200Y230700D01*
Y234100D01*
X247400Y235900D01*
Y238701D01*
X248178Y239479D01*
X257880D01*
X265002Y246601D01*
X266264Y249648D01*
X276530Y259914D01*
Y287312D01*
X277465Y288247D01*
Y288515D01*
X277500Y288550D01*
Y301012D01*
X278710Y302222D01*
Y303210D01*
X284300Y308800D01*
Y315509D01*
X289181Y320390D01*
X291000D01*
X291500Y320890D01*
Y329508D01*
X292200Y330208D01*
Y333400D01*
X290000Y335600D01*
G01X287050Y305850D02*
X285750D01*
X283800Y303900D01*
Y285872D01*
X279050Y281122D01*
Y274600D01*
X280050Y273600D01*
X288000D01*
X290140Y271460D01*
Y265840D01*
X277610Y253310D01*
X275450D01*
X274390Y252250D01*
Y250090D01*
X265492Y241192D01*
X264361Y238461D01*
X260700Y234800D01*
Y218700D01*
X257050Y215050D01*
X240600D01*
X238750Y213200D01*
X233820D01*
X233400Y212780D01*
Y208200D01*
X230300Y205100D01*
Y202800D01*
X229665Y202165D01*
X218565D01*
X216400Y200000D01*
Y194200D01*
X204100Y181900D01*
Y179700D01*
X202032Y177632D01*
Y174999D01*
X200253Y173220D01*
X195981D01*
X192584Y169823D01*
Y166482D01*
X192454Y166352D01*
Y161258D01*
X190944Y159748D01*
G01X187794Y153449D02*
X190349D01*
X191600Y154700D01*
X196817D01*
X197952Y155170D01*
X202000Y159218D01*
Y166701D01*
X202856Y167557D01*
X204457D01*
X205182Y168282D01*
Y169823D01*
X206359Y171000D01*
X209331D01*
X212217Y173886D01*
Y175977D01*
X216080Y179840D01*
Y182040D01*
X223912Y189872D01*
Y191912D01*
X225920Y193920D01*
X240160D01*
X240640Y194400D01*
X262588D01*
X275101Y199583D01*
X282778Y207260D01*
X286340D01*
X287744Y208664D01*
Y216636D01*
X295940Y224832D01*
Y274060D01*
X293800Y279227D01*
Y288101D01*
X292088Y292235D01*
X291000Y297700D01*
G01X287507Y301596D02*
X290304D01*
X293347Y298553D01*
Y295646D01*
X293104Y295403D01*
Y294398D01*
X293817Y293685D01*
X294823D01*
X295066Y293927D01*
X296072D01*
X300700Y289299D01*
Y288282D01*
X299988Y287570D01*
X298612D01*
X295800Y284758D01*
Y278580D01*
X297200Y275200D01*
Y224310D01*
X290800Y217910D01*
Y209500D01*
X287300Y206000D01*
X283300D01*
X275814Y198514D01*
X262744Y193100D01*
X228422D01*
X227062Y191740D01*
Y190618D01*
X226178Y189734D01*
X225055D01*
X224042Y188721D01*
Y188542D01*
X216900Y181400D01*
Y179500D01*
X213037Y175637D01*
Y173037D01*
X211400Y171400D01*
Y168618D01*
X210382Y167600D01*
X205900D01*
X205100Y166800D01*
Y159170D01*
X201154Y155224D01*
X195314Y152804D01*
X192400D01*
G01X289939Y309060D02*
Y305939D01*
X287700Y303700D01*
X286400D01*
X285200Y302500D01*
Y285490D01*
X280310Y280600D01*
Y275700D01*
X281150Y274860D01*
X288522D01*
X292400Y270982D01*
Y226300D01*
X282200Y216100D01*
Y211800D01*
X274578Y204178D01*
X269803Y202200D01*
X240200D01*
X237016Y199016D01*
X226215D01*
X226178Y199053D01*
X224926D01*
X224889Y199016D01*
X218627D01*
X217500Y197889D01*
Y193874D01*
X211481Y187855D01*
Y184448D01*
X210468Y183435D01*
X209346D01*
X208202Y182291D01*
Y181169D01*
X207318Y180285D01*
X206195D01*
X205182Y179272D01*
Y175000D01*
X204168Y173986D01*
X203266D01*
X201480Y172200D01*
X197700D01*
X196600Y171100D01*
Y169199D01*
X194913Y167512D01*
Y166866D01*
X194094Y166047D01*
G01X285911Y279569D02*
X288340Y277140D01*
X289960D01*
X294680Y272420D01*
Y225354D01*
X284500Y215174D01*
Y209720D01*
X283300Y208520D01*
X282256D01*
X274390Y200654D01*
X262430Y195700D01*
X240400D01*
X239440Y194740D01*
X223339D01*
X220800Y192201D01*
Y190581D01*
X219916Y189697D01*
X218296D01*
X217300Y188701D01*
Y184500D01*
X215260Y182460D01*
Y180180D01*
X211352Y176272D01*
Y174870D01*
X208582Y172100D01*
X203700D01*
X202000Y170400D01*
Y168600D01*
X201000Y167600D01*
X199700D01*
X198900Y166800D01*
Y166690D01*
X198883Y166673D01*
Y159183D01*
X197844Y158144D01*
X196443D01*
X194699Y156400D01*
X191400D01*
X189959Y154959D01*
X186155D01*
X184645Y153449D01*
G01X188546Y326356D02*
Y324646D01*
X189300Y323892D01*
Y305560D01*
X193380Y301480D01*
Y298547D01*
X188720Y293887D01*
Y290347D01*
X191307Y287760D01*
X198108D01*
X200310Y285558D01*
Y271427D01*
X199860Y270340D01*
X196600Y267080D01*
Y257321D01*
X194567Y255288D01*
G01X187400Y379400D02*
X189100Y377700D01*
Y354001D01*
X187220Y352121D01*
Y341743D01*
X185502Y340025D01*
Y323608D01*
X187979Y321131D01*
X187980D01*
Y300621D01*
X189660Y298941D01*
Y296694D01*
X187400Y294434D01*
Y289800D01*
X190760Y286440D01*
X197560D01*
X198790Y285210D01*
Y271762D01*
X198548Y271178D01*
X194800Y267430D01*
Y259116D01*
X193084Y257400D01*
G01X206200Y255385D02*
X207380Y256565D01*
Y260190D01*
X204542Y263028D01*
X203148Y266392D01*
X201230Y268310D01*
Y269612D01*
X202197Y271944D01*
Y285538D01*
X198455Y289280D01*
X191770D01*
X190040Y291010D01*
Y293340D01*
X194700Y298000D01*
Y302027D01*
X190638Y306089D01*
Y315738D01*
X194000Y319100D01*
Y337060D01*
X188540Y342520D01*
Y351574D01*
X189866Y352900D01*
X193790D01*
X197450Y356560D01*
G01X209842Y232151D02*
Y233123D01*
X206898Y236067D01*
Y243911D01*
X203941Y246868D01*
Y249041D01*
X208676Y253776D01*
X209500Y255766D01*
Y263400D01*
X208900Y264000D01*
Y269210D01*
X207310Y270800D01*
Y288700D01*
X204810Y291200D01*
X193080D01*
X192380Y291900D01*
G01X194600Y313300D02*
X195020Y313720D01*
Y332620D01*
X198070Y335670D01*
Y341329D01*
X194100Y345299D01*
Y348260D01*
X199260Y353420D01*
Y361707D01*
X197817Y363150D01*
X195556D01*
X192950Y365756D01*
Y368017D01*
X190420Y370547D01*
Y386820D01*
X192310Y388710D01*
Y399390D01*
X189140Y402560D01*
Y408962D01*
X190140Y409962D01*
X190270D01*
G01X199729Y314565D02*
X201570D01*
X202070Y315065D01*
Y319730D01*
X198490Y323310D01*
Y331890D01*
X202070Y335470D01*
Y339730D01*
X195900Y345900D01*
Y347439D01*
X197711Y349250D01*
G01X185000Y456500D02*
X185690Y455810D01*
X185750D01*
X186810Y454750D01*
Y453590D01*
X191700Y448700D01*
Y428800D01*
X196810Y423690D01*
Y420510D01*
X193700Y417400D01*
Y412300D01*
X197612Y408388D01*
Y394812D01*
X195190Y392390D01*
Y387856D01*
X193060Y385726D01*
Y371641D01*
X195590Y369111D01*
Y366850D01*
X196650Y365790D01*
X198911D01*
X203390Y361311D01*
Y311645D01*
X200340Y308595D01*
Y299810D01*
X209982Y290168D01*
Y272829D01*
X214355Y268456D01*
Y264475D01*
X211755Y261875D01*
Y258053D01*
X213655Y256153D01*
Y250293D01*
X212120Y248758D01*
Y240100D01*
X214910Y237310D01*
Y231779D01*
X213688Y230557D01*
X211772D01*
X211352Y230137D01*
Y222051D01*
X210401Y221100D01*
X201940D01*
X200393Y219553D01*
G01X197775Y346617D02*
X200580Y349422D01*
Y362254D01*
X198364Y364470D01*
X196103D01*
X194270Y366303D01*
Y368564D01*
X191740Y371094D01*
Y386273D01*
X193870Y388403D01*
Y401082D01*
X194500Y402600D01*
G01X198405Y434800D02*
X197100Y433495D01*
Y433087D01*
X197110Y433077D01*
Y431409D01*
X196200Y430499D01*
Y426167D01*
X198130Y424237D01*
Y418807D01*
X203692Y413245D01*
X206428Y406638D01*
X208565Y404501D01*
G01X342200Y100500D02*
X346640Y96060D01*
Y81083D01*
X332077Y66520D01*
X305077D01*
X293657Y55100D01*
X265100D01*
X261100Y51100D01*
X207698D01*
X203396Y55402D01*
Y55996D01*
X204300Y56900D01*
Y60600D01*
G01X342180Y106900D02*
X347660Y101420D01*
Y80660D01*
X332500Y65500D01*
X305500D01*
X294080Y54080D01*
X265523D01*
X261523Y50080D01*
X207275D01*
X202376Y54979D01*
Y55996D01*
X201472Y56900D01*
Y60972D01*
X201500Y61000D01*
G01X197853Y307200D02*
Y300695D01*
X208700Y289853D01*
Y272569D01*
X213274Y267995D01*
Y264962D01*
X210546Y262234D01*
Y257553D01*
X212563Y255536D01*
Y250764D01*
X211100Y249301D01*
Y239150D01*
X212991Y237259D01*
Y232151D01*
G01X205900Y266130D02*
Y264183D01*
X206625Y262433D01*
X208400Y260658D01*
Y255966D01*
X207718Y254319D01*
X202869Y249470D01*
Y245965D01*
X205652Y243182D01*
Y235827D01*
X208223Y233256D01*
Y231557D01*
X209100Y230680D01*
Y229744D01*
X209842Y229002D01*
G01X206430Y298780D02*
X206960Y299310D01*
X222860D01*
X227287Y294883D01*
Y279287D01*
X224300Y276300D01*
Y263135D01*
X222833Y261668D01*
G01X208628Y324665D02*
Y355202D01*
X215900Y372761D01*
Y378432D01*
X205775Y402877D01*
Y403981D01*
X202317Y412327D01*
X199244Y415400D01*
X197600D01*
G01X213490Y373690D02*
Y380016D01*
X203930Y403095D01*
X203934Y403106D01*
X200000Y407040D01*
G01X207278Y416022D02*
X211100Y412200D01*
Y403910D01*
X208330Y401140D01*
X217415Y379209D01*
X217520Y379104D01*
Y372438D01*
X213430Y362562D01*
Y342270D01*
X216405Y339295D01*
Y335970D01*
G01X221278Y129294D02*
X222106D01*
X223400Y128000D01*
Y124100D01*
X222200Y122900D01*
X221700D01*
X218500Y119700D01*
X215200D01*
X213300Y117800D01*
Y112600D01*
X212400Y111700D01*
Y105500D01*
X219320Y98580D01*
X231180D01*
X232325Y99725D01*
Y101230D01*
G01X225284Y129294D02*
X227442Y127136D01*
Y121742D01*
X226950Y121250D01*
X222150D01*
X216800Y115900D01*
Y113000D01*
X214300Y110500D01*
Y105900D01*
X216860Y103340D01*
X223920D01*
X226040Y101220D01*
G01X225658Y153369D02*
Y146542D01*
X237800Y134400D01*
X246926D01*
X247426Y133900D01*
Y124926D01*
X244000Y121500D01*
X241290D01*
X237640Y117850D01*
Y116899D01*
X236978Y115301D01*
Y113431D01*
X238109Y112300D01*
X239206D01*
G01X227232Y270539D02*
X228240Y269531D01*
Y265597D01*
X227783Y265140D01*
Y260480D01*
X231534Y256729D01*
X231810Y256063D01*
Y254309D01*
X227400Y249899D01*
Y240056D01*
X224000Y236656D01*
Y227442D01*
X225590Y225852D01*
G01X226405Y266335D02*
Y262176D01*
X225506Y261277D01*
Y255894D01*
X226400Y255000D01*
Y253200D01*
X223307Y250107D01*
Y237123D01*
X220800Y234616D01*
Y225101D01*
X219290Y223591D01*
Y222703D01*
G01X230287Y373100D02*
X230170Y372983D01*
Y358506D01*
X223200Y351536D01*
Y344726D01*
X223210Y344716D01*
Y342884D01*
X223200Y342874D01*
Y342000D01*
X222120Y340920D01*
Y333396D01*
X220100Y331376D01*
Y318999D01*
X222183Y316916D01*
Y302717D01*
X228600Y296300D01*
Y296168D01*
X228608Y296160D01*
Y295068D01*
X228607Y295067D01*
Y283863D01*
X229220Y283250D01*
G01X231900Y272700D02*
Y288733D01*
X230220Y290413D01*
Y298381D01*
X226000Y302601D01*
Y315300D01*
X221420Y319880D01*
Y330829D01*
X223440Y332849D01*
Y338440D01*
X228100Y343100D01*
Y353876D01*
X231490Y357266D01*
Y360028D01*
X235420Y363958D01*
Y372240D01*
X226605Y381055D01*
Y389296D01*
X225396Y390505D01*
Y401322D01*
X223985Y402733D01*
X221987D01*
X220134Y400880D01*
Y400780D01*
G01X227206Y400100D02*
Y397734D01*
X230040Y394900D01*
Y382150D01*
X231720Y380470D01*
X233809D01*
X236740Y377539D01*
Y366922D01*
X237840Y364265D01*
Y341307D01*
X235053Y338520D01*
X230053D01*
X224780Y333247D01*
Y333081D01*
X224760Y333061D01*
Y332302D01*
X222740Y330282D01*
Y321260D01*
X231540Y312460D01*
Y290960D01*
X234858Y287642D01*
Y253657D01*
X230535Y249334D01*
Y244564D01*
G01X217300Y322800D02*
Y323900D01*
X218300Y324900D01*
Y331868D01*
X220500Y334068D01*
Y340680D01*
X218279Y342901D01*
Y366159D01*
X220700Y372003D01*
Y381600D01*
X224985Y385885D01*
Y388624D01*
X222986Y390623D01*
Y400323D01*
G01X235400Y303800D02*
Y308899D01*
X233500Y310799D01*
Y312400D01*
X224060Y321840D01*
Y329734D01*
X226100Y331774D01*
Y332700D01*
X230600Y337200D01*
X235600D01*
X239160Y340760D01*
Y364528D01*
X238060Y367185D01*
Y378086D01*
X237230Y378916D01*
Y382080D01*
X234820Y384490D01*
X233790D01*
G01X213900Y436000D02*
Y401600D01*
X217500Y398000D01*
Y392700D01*
X222575Y387625D01*
G01X224000Y449100D02*
X222640D01*
X220110Y446570D01*
Y427590D01*
X221400Y426300D01*
Y414860D01*
X224930Y411330D01*
Y406780D01*
X227206Y404504D01*
Y400100D01*
G01X231400Y449500D02*
X229420D01*
X229000Y449080D01*
Y446147D01*
X231599Y443550D01*
Y442798D01*
X227678Y438877D01*
X226925D01*
X226391Y439411D01*
Y440165D01*
X229024Y442798D01*
Y443550D01*
X228489Y444085D01*
X227736D01*
X225102Y441451D01*
X224349D01*
X223815Y441985D01*
Y442739D01*
X226448Y445372D01*
Y446124D01*
X225913Y446659D01*
X225160D01*
X221800Y443299D01*
Y439063D01*
X222333Y438530D01*
X224767D01*
X225300Y437997D01*
Y437243D01*
X224767Y436710D01*
X222333D01*
X221800Y436177D01*
Y428600D01*
X223100Y427300D01*
Y416300D01*
X227864Y411536D01*
Y410782D01*
X226619Y409537D01*
Y408783D01*
X227152Y408250D01*
X227906D01*
X229151Y409495D01*
X229905D01*
X232200Y407200D01*
Y391078D01*
X231990Y390868D01*
Y389162D01*
X233222Y387930D01*
X235602D01*
X238850Y384682D01*
Y379588D01*
X239680Y378758D01*
Y367508D01*
X240780Y364851D01*
Y333723D01*
X239162Y332105D01*
Y330714D01*
X237970Y329522D01*
Y322938D01*
X240700Y320208D01*
Y320100D01*
X242580Y318220D01*
Y313218D01*
X247000Y308798D01*
Y306100D01*
X245900Y305000D01*
G01X235630Y104990D02*
X234900Y105720D01*
Y107550D01*
X237080Y109730D01*
X240330D01*
X242196Y111596D01*
Y114196D01*
X242900Y114900D01*
Y114909D01*
X244311Y116320D01*
X244320D01*
X244790Y116790D01*
Y118399D01*
X248907Y122516D01*
Y135090D01*
X248277Y135720D01*
X238347D01*
X229510Y144557D01*
Y152650D01*
X227142Y155018D01*
Y161338D01*
X228702Y162898D01*
G01X260050Y87026D02*
X256086Y90990D01*
Y94095D01*
X258383Y96392D01*
X261870D01*
X263781Y98303D01*
Y99879D01*
X262650Y101010D01*
Y106010D01*
X258151Y110509D01*
Y120644D01*
X255690Y123105D01*
Y127166D01*
X258286Y129762D01*
Y135376D01*
X241300Y152362D01*
Y159748D01*
G01X247689Y247929D02*
X242396D01*
X239347Y244880D01*
X237613D01*
X232700Y239967D01*
Y233601D01*
X236548Y229753D01*
Y228413D01*
X235038Y226903D01*
Y225890D01*
G01X241188Y279347D02*
X240400Y278559D01*
Y278000D01*
X236700Y274300D01*
Y266300D01*
X237100Y265900D01*
X240380D01*
X240800Y265480D01*
Y259500D01*
X240100Y258800D01*
Y256400D01*
X233303Y249603D01*
Y244504D01*
X229740Y240941D01*
Y239086D01*
X228600Y237946D01*
Y231240D01*
X230212Y229628D01*
Y227567D01*
X231889Y225890D01*
G01X228702Y229002D02*
X227300Y230404D01*
Y238513D01*
X228420Y239633D01*
Y249220D01*
X232830Y253630D01*
Y256266D01*
X232399Y257307D01*
X229630Y260076D01*
Y264404D01*
G01X245900Y305000D02*
Y303600D01*
X249000Y300500D01*
Y292400D01*
X247900Y291300D01*
Y272800D01*
X250000Y270700D01*
Y268800D01*
X247700Y266500D01*
Y252820D01*
X244680Y249800D01*
X239445D01*
X237730Y248085D01*
G01X248900Y304900D02*
Y309190D01*
X244200Y313890D01*
Y319000D01*
X239590Y323610D01*
Y328850D01*
X240782Y330042D01*
Y331433D01*
X242400Y333051D01*
Y365174D01*
X241300Y367831D01*
Y379430D01*
X240470Y380260D01*
Y387150D01*
X234790Y392830D01*
Y395210D01*
X235900Y397890D01*
X237134Y399124D01*
X240008Y406063D01*
X241231Y407285D01*
G01X247923Y316400D02*
X250000Y318477D01*
Y321247D01*
X247923Y323324D01*
Y332066D01*
X247500Y333087D01*
Y334226D01*
X247440Y334286D01*
Y376386D01*
X245706Y378120D01*
X244053D01*
X241490Y380683D01*
Y387573D01*
X236670Y392393D01*
Y394550D01*
G01X231400Y452000D02*
X232880D01*
X233300Y451580D01*
Y448101D01*
X235853Y445548D01*
X240169Y443760D01*
X254780Y429149D01*
Y406430D01*
X253490Y405140D01*
Y394435D01*
X252657Y393602D01*
X252020D01*
X251600Y393182D01*
Y392202D01*
X252020Y391782D01*
X252657D01*
X253190Y391249D01*
Y390495D01*
X252657Y389962D01*
X250033D01*
X249500Y389429D01*
Y388675D01*
X250033Y388142D01*
X252657D01*
X253490Y387309D01*
Y352082D01*
X252800Y350416D01*
Y347292D01*
X252680Y347172D01*
Y336020D01*
X258964Y329736D01*
X260400Y325428D01*
Y322925D01*
X259867Y322392D01*
X257833D01*
X257300Y321859D01*
Y321105D01*
X257833Y320572D01*
X259867D01*
X260400Y320039D01*
Y319285D01*
X259867Y318752D01*
X257833D01*
X257300Y318219D01*
Y317465D01*
X257833Y316932D01*
X259867D01*
X260400Y316399D01*
Y309334D01*
X256041Y298809D01*
Y294579D01*
X257970Y292650D01*
X262416D01*
X264310Y290756D01*
Y279784D01*
X263016Y278490D01*
X259190D01*
X256000Y275300D01*
Y272000D01*
X250654Y266654D01*
Y257365D01*
X253110Y254909D01*
G01X259500Y263700D02*
Y265100D01*
X259900Y265500D01*
Y269146D01*
X263650Y272896D01*
Y274540D01*
X267550Y278440D01*
Y293250D01*
X268100Y293800D01*
Y303918D01*
X270010Y305828D01*
Y327779D01*
X268100Y329689D01*
Y330404D01*
X267020Y331484D01*
Y333762D01*
X265900Y334882D01*
Y334890D01*
X264250Y336540D01*
Y348250D01*
X258050Y354450D01*
Y403230D01*
X259340Y404520D01*
Y408987D01*
X259873Y409520D01*
X261667D01*
X262200Y410053D01*
Y410807D01*
X261667Y411340D01*
X259873D01*
X259340Y411873D01*
Y412627D01*
X259873Y413160D01*
X261667D01*
X262200Y413693D01*
Y414447D01*
X261667Y414980D01*
X259873D01*
X259340Y415513D01*
Y416267D01*
X259873Y416800D01*
X261667D01*
X262200Y417333D01*
Y418087D01*
X261667Y418620D01*
X259873D01*
X259340Y419153D01*
Y433340D01*
X259620Y433620D01*
Y435881D01*
X256992Y438509D01*
X256239D01*
X254793Y437063D01*
X254039D01*
X253505Y437597D01*
Y438349D01*
X254953Y439796D01*
Y440548D01*
X254418Y441083D01*
X253665D01*
X252219Y439637D01*
X251465D01*
X250931Y440171D01*
Y440923D01*
X252379Y442370D01*
Y443122D01*
X251844Y443657D01*
X251091D01*
X249645Y442211D01*
X248891D01*
X248357Y442745D01*
Y443497D01*
X249805Y444944D01*
Y445696D01*
X249000Y446501D01*
Y454500D01*
X247500Y456000D01*
X240010D01*
G01X240210Y453400D02*
X238520D01*
X238100Y453820D01*
Y457580D01*
X238520Y458000D01*
X248100D01*
X250959Y455141D01*
Y446940D01*
X261600Y436299D01*
Y432901D01*
X261400Y432701D01*
Y424299D01*
X266200Y419499D01*
Y409080D01*
X259670Y402550D01*
Y355122D01*
X265870Y348922D01*
Y337212D01*
X267520Y335562D01*
Y335554D01*
X268640Y334434D01*
Y332156D01*
X271630Y329166D01*
Y305156D01*
X269720Y303246D01*
Y293128D01*
X269170Y292578D01*
Y277768D01*
X265270Y273868D01*
Y272223D01*
X262700Y269653D01*
Y267630D01*
X262730Y267600D01*
G01X272505Y83545D02*
Y83695D01*
X272810Y84000D01*
Y85690D01*
X269482Y89018D01*
Y110853D01*
X261426Y118909D01*
Y121358D01*
X258557Y124227D01*
Y125732D01*
X261702Y128877D01*
Y130495D01*
X262235Y131028D01*
Y132965D01*
X259020Y136180D01*
Y142228D01*
X256500Y144748D01*
Y147800D01*
X257550Y148850D01*
Y164920D01*
X254840Y167630D01*
X253140D01*
X252350Y166840D01*
Y165240D01*
X251640Y164530D01*
X249269D01*
X247637Y162898D01*
G01X247599Y166047D02*
X248257D01*
X249890Y167680D01*
X251480D01*
X252370Y168570D01*
Y170170D01*
X252950Y170750D01*
X254600D01*
X258570Y166780D01*
Y148891D01*
X260710Y146751D01*
Y136291D01*
X263255Y133746D01*
Y130605D01*
X262737Y130087D01*
Y119221D01*
X270502Y111456D01*
Y89441D01*
X274633Y85310D01*
X275740D01*
X277505Y83545D01*
G01X244450Y169197D02*
X246047Y167600D01*
X248650D01*
X249110Y168060D01*
Y173110D01*
X249980Y173980D01*
X257660D01*
X259590Y172050D01*
Y149314D01*
X261730Y147174D01*
Y136770D01*
X264275Y134225D01*
Y127314D01*
X263860Y126899D01*
Y119673D01*
X271522Y112011D01*
Y89864D01*
X275056Y86330D01*
X277680D01*
X280515Y83495D01*
X282455D01*
X282505Y83545D01*
G01X246500Y448500D02*
X247300Y447700D01*
Y444732D01*
X246737Y444169D01*
Y442073D01*
X247300Y441510D01*
Y441300D01*
X257720Y430880D01*
Y405200D01*
X256430Y403910D01*
Y353778D01*
X262630Y347578D01*
Y335860D01*
X265400Y333090D01*
Y330097D01*
X268390Y327107D01*
Y306500D01*
X262900Y301010D01*
Y294458D01*
X265930Y291428D01*
Y279112D01*
X263688Y276870D01*
X259870D01*
X258100Y275100D01*
Y271599D01*
X253100Y266599D01*
Y257800D01*
G01X242592Y330683D02*
X242700D01*
Y329548D01*
X245400Y326848D01*
Y314591D01*
X250710Y309281D01*
Y293600D01*
X255160Y289150D01*
X258000Y284900D01*
G01X252350Y412850D02*
X253160Y412040D01*
Y407102D01*
X251870Y405812D01*
Y398470D01*
X246300Y392900D01*
Y383792D01*
X250370Y379722D01*
Y335830D01*
X255300Y330900D01*
Y328969D01*
X254591Y328260D01*
X254009D01*
X253300Y327551D01*
Y326549D01*
X254009Y325840D01*
X255160D01*
X255902Y325098D01*
Y322678D01*
X255490Y322266D01*
Y303318D01*
X254355Y300577D01*
G01X243375Y448375D02*
Y443225D01*
X256400Y430200D01*
Y405750D01*
X255110Y404460D01*
Y347310D01*
X254300Y346500D01*
Y342470D01*
X258010Y338760D01*
Y334790D01*
X259790Y333010D01*
Y332950D01*
X260850Y331890D01*
X260910D01*
X262570Y330230D01*
X263400D01*
X266740Y326890D01*
Y314800D01*
X265700Y313760D01*
Y310300D01*
X261110Y305710D01*
Y298090D01*
X258100Y295080D01*
G01X276660Y316900D02*
Y325960D01*
X278000Y327300D01*
Y334600D01*
X276500Y336100D01*
X272667D01*
X267490Y341277D01*
Y349594D01*
X261290Y355794D01*
Y401878D01*
X267820Y408408D01*
Y414620D01*
X271500Y418300D01*
G01X278409Y433722D02*
Y425809D01*
X273310Y420710D01*
Y412100D01*
X272200Y410990D01*
Y407988D01*
X268700Y404488D01*
Y368490D01*
X270735Y366455D01*
X276145D01*
G01X300700Y341300D02*
Y382400D01*
X304000Y385700D01*
X317200D01*
X324700Y393200D01*
X327200D01*
X331400Y389000D01*
X342100D01*
X346700Y384400D01*
Y352300D01*
X335096Y340696D01*
Y317184D01*
X345463Y306817D01*
Y118763D01*
X342100Y115400D01*
X331979D01*
X318200Y101621D01*
Y97167D01*
X315580Y94547D01*
Y92747D01*
X313253Y90420D01*
X292039D01*
X291119Y89500D01*
X283500D01*
G01X302879Y282487D02*
X305000Y284608D01*
Y290200D01*
X292000Y303200D01*
Y309800D01*
X288100Y313700D01*
Y315460D01*
X290378Y317738D01*
X292037D01*
X295000Y320701D01*
Y332001D01*
X297500Y334501D01*
Y359100D01*
X283700Y372900D01*
Y379236D01*
X283664D01*
G01X345500Y342690D02*
X344996Y342186D01*
X341866D01*
X336416Y336736D01*
Y317731D01*
X346783Y307364D01*
Y114783D01*
X342700Y110700D01*
X336900D01*
X336200Y110000D01*
Y104500D01*
X334300Y102600D01*
X325500D01*
X316900Y94000D01*
Y92200D01*
X313800Y89100D01*
X292586D01*
X287578Y84092D01*
G01X309700Y294789D02*
Y310255D01*
X305950Y314005D01*
X293195D01*
X291300Y315900D01*
M02*
